FILE_TYPE = MACRO_DRAWING;
SET COLOR_WIRE YELLOW;
SET COLOR_PROP ORANGE;
SET COLOR_DOT WHITE;
SET COLOR_ARC YELLOW;
SET COLOR_BODY GREEN;
SET COLOR_NOTE PURPLE;
SET PROP_DISPLAY VALUE;
SET PAGE_NUMBER P165;
FORCEADD GND..1
(-3275 -1650);
FORCEPROP 3 LASTPIN (-3275 -1600) SIG_NAME GND\g
J 0
(-3265 -1590);
DISPLAY 0.659574 (-3265 -1590);
PAINT MONO (-3265 -1590);
DISPLAY INVISIBLE (-3265 -1590);
FORCEPROP 1 LAST PATH I1
J 0
(-3200 -1650);
DISPLAY 0.872340 (-3200 -1650);
PAINT AQUA (-3200 -1650);
DISPLAY INVISIBLE (-3200 -1650);
FORCEPROP 1 LAST HDL_POWER GND
J 0
(-3275 -1500);
DISPLAY 0.872340 (-3275 -1500);
PAINT GREEN (-3275 -1500);
DISPLAY INVISIBLE (-3275 -1500);
FORCEPROP 1 LAST SIZE 1B
J 0
(-3200 -1700);
DISPLAY 0.872340 (-3200 -1700);
PAINT AQUA (-3200 -1700);
DISPLAY INVISIBLE (-3200 -1700);
FORCEPROP 2 LAST CDS_LIB pure_quanta_power
J 0
(-3275 -1650);
DISPLAY INVISIBLE (-3275 -1650);
FORCEADD GND..1
(-2125 -1325);
FORCEPROP 3 LASTPIN (-2125 -1275) SIG_NAME GND\g
J 0
(-2115 -1265);
DISPLAY 0.659574 (-2115 -1265);
PAINT MONO (-2115 -1265);
DISPLAY INVISIBLE (-2115 -1265);
FORCEPROP 1 LAST PATH I10
J 0
(-2050 -1325);
DISPLAY 0.872340 (-2050 -1325);
PAINT AQUA (-2050 -1325);
DISPLAY INVISIBLE (-2050 -1325);
FORCEPROP 1 LAST HDL_POWER GND
J 0
(-2125 -1175);
DISPLAY 0.872340 (-2125 -1175);
PAINT GREEN (-2125 -1175);
DISPLAY INVISIBLE (-2125 -1175);
FORCEPROP 2 LAST CDS_LIB pure_quanta_power
J 0
(-2125 -1325);
DISPLAY INVISIBLE (-2125 -1325);
FORCEPROP 1 LAST SIZE 1B
J 0
(-2050 -1375);
DISPLAY 0.872340 (-2050 -1375);
PAINT AQUA (-2050 -1375);
DISPLAY INVISIBLE (-2050 -1375);
FORCEADD Q_RES..2
(-2125 -1150);
FORCEPROP 1 LAST LOCATION PR832
J 0
(-2080 -1025);
DISPLAY 0.617021 (-2080 -1025);
PAINT AQUA (-2080 -1025);
FORCEPROP 0 LAST $SEC 1
J 0
(-2075 -975);
DISPLAY 0.680851 (-2075 -975);
PAINT MONO (-2075 -975);
DISPLAY INVISIBLE (-2075 -975);
FORCEPROP 0 LAST CDS_SEC 1
J 0
(-2075 -975);
DISPLAY 1.021277 (-2075 -975);
DISPLAY INVISIBLE (-2075 -975);
FORCEPROP 1 LASTPIN (-2125 -1050) $PN 1
J 0
(-2120 -1088);
DISPLAY 0.617021 (-2120 -1088);
PAINT MONO (-2120 -1088);
FORCEPROP 1 LASTPIN (-2125 -1250) $PN 2
J 0
(-2120 -1240);
DISPLAY 0.617021 (-2120 -1240);
PAINT MONO (-2120 -1240);
FORCEPROP 1 LAST MATERIAL CHIP
J 0
(-2085 -1225);
DISPLAY 0.617021 (-2085 -1225);
PAINT SKYBLUE (-2085 -1225);
FORCEPROP 1 LAST WATTAGE 1/16W
J 0
(-2085 -1175);
DISPLAY 0.617021 (-2085 -1175);
PAINT SKYBLUE (-2085 -1175);
FORCEPROP 1 LAST TOLERANCE 5%
J 0
(-2080 -1125);
DISPLAY 0.617021 (-2080 -1125);
PAINT SKYBLUE (-2080 -1125);
FORCEPROP 1 LAST PACK_TYPE 0402LF
J 0
(-2085 -1325);
DISPLAY 0.617021 (-2085 -1325);
PAINT SKYBLUE (-2085 -1325);
FORCEPROP 1 LAST PART_NUMBER CS00002JB13
J 0
(-2085 -1275);
DISPLAY 0.617021 (-2085 -1275);
PAINT BLUE (-2085 -1275);
FORCEPROP 1 LAST VALUE 0
J 0
(-2080 -1075);
DISPLAY 0.617021 (-2080 -1075);
PAINT SKYBLUE (-2080 -1075);
FORCEPROP 1 LAST PATH I11
J 0
(-2075 -975);
DISPLAY 0.978723 (-2075 -975);
PAINT WHITE (-2075 -975);
DISPLAY INVISIBLE (-2075 -975);
FORCEPROP 2 LAST CDS_LIB pure_quanta
J 0
(-2125 -1150);
DISPLAY INVISIBLE (-2125 -1150);
FORCEADD GND..1
(-1725 -1450);
FORCEPROP 3 LASTPIN (-1725 -1400) SIG_NAME GND\g
J 0
(-1715 -1390);
DISPLAY 0.659574 (-1715 -1390);
PAINT MONO (-1715 -1390);
DISPLAY INVISIBLE (-1715 -1390);
FORCEPROP 1 LAST PATH I12
J 0
(-1650 -1450);
DISPLAY 0.872340 (-1650 -1450);
PAINT AQUA (-1650 -1450);
DISPLAY INVISIBLE (-1650 -1450);
FORCEPROP 1 LAST HDL_POWER GND
J 0
(-1725 -1300);
DISPLAY 0.872340 (-1725 -1300);
PAINT GREEN (-1725 -1300);
DISPLAY INVISIBLE (-1725 -1300);
FORCEPROP 1 LAST SIZE 1B
J 0
(-1650 -1500);
DISPLAY 0.872340 (-1650 -1500);
PAINT AQUA (-1650 -1500);
DISPLAY INVISIBLE (-1650 -1500);
FORCEPROP 2 LAST CDS_LIB pure_quanta_power
J 0
(-1725 -1450);
DISPLAY INVISIBLE (-1725 -1450);
FORCEADD Q_RES..2
(-1725 -1250);
FORCEPROP 1 LAST LOCATION PR833
J 0
(-1680 -1125);
DISPLAY 0.617021 (-1680 -1125);
PAINT AQUA (-1680 -1125);
FORCEPROP 0 LAST $SEC 1
J 0
(-1675 -1075);
DISPLAY 0.680851 (-1675 -1075);
PAINT MONO (-1675 -1075);
DISPLAY INVISIBLE (-1675 -1075);
FORCEPROP 0 LAST CDS_SEC 1
J 0
(-1675 -1075);
DISPLAY 1.021277 (-1675 -1075);
DISPLAY INVISIBLE (-1675 -1075);
FORCEPROP 1 LASTPIN (-1725 -1150) $PN 1
J 0
(-1720 -1188);
DISPLAY 0.617021 (-1720 -1188);
PAINT MONO (-1720 -1188);
FORCEPROP 1 LASTPIN (-1725 -1350) $PN 2
J 0
(-1720 -1340);
DISPLAY 0.617021 (-1720 -1340);
PAINT MONO (-1720 -1340);
FORCEPROP 1 LAST VALUE 1.5K
J 0
(-1680 -1175);
DISPLAY 0.617021 (-1680 -1175);
PAINT SKYBLUE (-1680 -1175);
FORCEPROP 1 LAST PACK_TYPE 0402LF
J 0
(-1685 -1425);
DISPLAY 0.617021 (-1685 -1425);
PAINT SKYBLUE (-1685 -1425);
FORCEPROP 1 LAST MATERIAL EMPTY
J 0
(-1685 -1325);
DISPLAY 0.617021 (-1685 -1325);
PAINT RED (-1685 -1325);
FORCEPROP 1 LAST TOLERANCE 1%
J 0
(-1680 -1225);
DISPLAY 0.617021 (-1680 -1225);
PAINT SKYBLUE (-1680 -1225);
FORCEPROP 1 LAST WATTAGE 1/16W
J 0
(-1685 -1275);
DISPLAY 0.617021 (-1685 -1275);
PAINT SKYBLUE (-1685 -1275);
FORCEPROP 1 LAST PART_NUMBER CS21502FB07
J 0
(-1700 -1375);
DISPLAY 0.617021 (-1700 -1375);
PAINT BLUE (-1700 -1375);
FORCEPROP 1 LAST PATH I13
J 0
(-1675 -1075);
DISPLAY 0.978723 (-1675 -1075);
PAINT WHITE (-1675 -1075);
DISPLAY INVISIBLE (-1675 -1075);
FORCEPROP 2 LAST CDS_LIB pure_quanta
J 0
(-1725 -1250);
DISPLAY INVISIBLE (-1725 -1250);
FORCEADD GND..1
(-1325 -1550);
FORCEPROP 3 LASTPIN (-1325 -1500) SIG_NAME GND\g
J 0
(-1315 -1490);
DISPLAY 0.659574 (-1315 -1490);
PAINT MONO (-1315 -1490);
DISPLAY INVISIBLE (-1315 -1490);
FORCEPROP 1 LAST PATH I14
J 0
(-1250 -1550);
DISPLAY 0.872340 (-1250 -1550);
PAINT AQUA (-1250 -1550);
DISPLAY INVISIBLE (-1250 -1550);
FORCEPROP 1 LAST HDL_POWER GND
J 0
(-1325 -1400);
DISPLAY 0.872340 (-1325 -1400);
PAINT GREEN (-1325 -1400);
DISPLAY INVISIBLE (-1325 -1400);
FORCEPROP 2 LAST CDS_LIB pure_quanta_power
J 0
(-1325 -1550);
DISPLAY INVISIBLE (-1325 -1550);
FORCEPROP 1 LAST SIZE 1B
J 0
(-1250 -1600);
DISPLAY 0.872340 (-1250 -1600);
PAINT AQUA (-1250 -1600);
DISPLAY INVISIBLE (-1250 -1600);
FORCEADD Q_RES..2
(-1325 -1350);
FORCEPROP 1 LAST LOCATION PR834
J 0
(-1275 -1225);
DISPLAY 0.617021 (-1275 -1225);
PAINT AQUA (-1275 -1225);
FORCEPROP 0 LAST $SEC 1
J 0
(-1275 -1175);
DISPLAY 0.680851 (-1275 -1175);
PAINT MONO (-1275 -1175);
DISPLAY INVISIBLE (-1275 -1175);
FORCEPROP 0 LAST CDS_SEC 1
J 0
(-1275 -1175);
DISPLAY 1.021277 (-1275 -1175);
DISPLAY INVISIBLE (-1275 -1175);
FORCEPROP 1 LASTPIN (-1325 -1250) $PN 1
J 0
(-1320 -1288);
DISPLAY 0.617021 (-1320 -1288);
PAINT MONO (-1320 -1288);
FORCEPROP 1 LASTPIN (-1325 -1450) $PN 2
J 0
(-1320 -1440);
DISPLAY 0.617021 (-1320 -1440);
PAINT MONO (-1320 -1440);
FORCEPROP 1 LAST VALUE 21.5K
J 0
(-1275 -1275);
DISPLAY 0.617021 (-1275 -1275);
PAINT SKYBLUE (-1275 -1275);
FORCEPROP 1 LAST MATERIAL CHIP
J 0
(-1280 -1425);
DISPLAY 0.617021 (-1280 -1425);
PAINT SKYBLUE (-1280 -1425);
FORCEPROP 1 LAST PART_NUMBER CS32152FB04
J 0
(-1280 -1475);
DISPLAY 0.617021 (-1280 -1475);
PAINT BLUE (-1280 -1475);
FORCEPROP 1 LAST PACK_TYPE 0402LF
J 0
(-1275 -1525);
DISPLAY 0.617021 (-1275 -1525);
PAINT SKYBLUE (-1275 -1525);
FORCEPROP 1 LAST TOLERANCE 1%
J 0
(-1275 -1325);
DISPLAY 0.617021 (-1275 -1325);
PAINT SKYBLUE (-1275 -1325);
FORCEPROP 1 LAST WATTAGE 1/16W
J 0
(-1280 -1375);
DISPLAY 0.617021 (-1280 -1375);
PAINT SKYBLUE (-1280 -1375);
FORCEPROP 1 LAST PATH I15
J 0
(-1275 -1175);
DISPLAY 0.978723 (-1275 -1175);
PAINT WHITE (-1275 -1175);
DISPLAY INVISIBLE (-1275 -1175);
FORCEPROP 2 LAST CDS_LIB pure_quanta
J 0
(-1325 -1350);
DISPLAY INVISIBLE (-1325 -1350);
FORCEADD GND..1
(-2025 -775);
FORCEPROP 3 LASTPIN (-2025 -725) SIG_NAME GND\g
J 0
(-2015 -715);
DISPLAY 0.659574 (-2015 -715);
PAINT MONO (-2015 -715);
DISPLAY INVISIBLE (-2015 -715);
FORCEPROP 1 LAST PATH I16
J 0
(-1950 -775);
DISPLAY 0.872340 (-1950 -775);
PAINT AQUA (-1950 -775);
DISPLAY INVISIBLE (-1950 -775);
FORCEPROP 1 LAST HDL_POWER GND
J 0
(-2025 -625);
DISPLAY 0.872340 (-2025 -625);
PAINT GREEN (-2025 -625);
DISPLAY INVISIBLE (-2025 -625);
FORCEPROP 2 LAST CDS_LIB pure_quanta_power
J 0
(-2025 -775);
DISPLAY INVISIBLE (-2025 -775);
FORCEPROP 1 LAST SIZE 1B
J 0
(-1950 -825);
DISPLAY 0.872340 (-1950 -825);
PAINT AQUA (-1950 -825);
DISPLAY INVISIBLE (-1950 -825);
FORCEADD Q_CAP..1
(-2025 -550);
FORCEPROP 1 LAST LOCATION PC581
J 0
(-1975 -450);
DISPLAY 0.617021 (-1975 -450);
PAINT AQUA (-1975 -450);
FORCEPROP 0 LAST $SEC 1
J 0
(-1975 -400);
DISPLAY 0.680851 (-1975 -400);
PAINT MONO (-1975 -400);
DISPLAY INVISIBLE (-1975 -400);
FORCEPROP 0 LAST CDS_SEC 1
J 0
(-1975 -400);
DISPLAY 1.021277 (-1975 -400);
DISPLAY INVISIBLE (-1975 -400);
FORCEPROP 1 LASTPIN (-2025 -450) $PN 1
J 0
(-2015 -470);
DISPLAY 0.617021 (-2015 -470);
PAINT MONO (-2015 -470);
FORCEPROP 1 LASTPIN (-2025 -650) $PN 2
J 0
(-2015 -670);
DISPLAY 0.617021 (-2015 -670);
PAINT MONO (-2015 -670);
FORCEPROP 1 LAST MATERIAL X6S
J 0
(-1975 -650);
DISPLAY 0.617021 (-1975 -650);
PAINT SKYBLUE (-1975 -650);
FORCEPROP 1 LAST VALUE 4.7UF
J 0
(-1975 -500);
DISPLAY 0.617021 (-1975 -500);
PAINT SKYBLUE (-1975 -500);
FORCEPROP 1 LAST TOLERANCE 10%
J 0
(-1975 -600);
DISPLAY 0.617021 (-1975 -600);
PAINT SKYBLUE (-1975 -600);
FORCEPROP 1 LAST PART_NUMBER CH5473KE902
J 0
(-1975 -700);
DISPLAY 0.617021 (-1975 -700);
PAINT BLUE (-1975 -700);
FORCEPROP 1 LAST VOLTAGE 16V
J 0
(-1975 -550);
DISPLAY 0.617021 (-1975 -550);
PAINT SKYBLUE (-1975 -550);
FORCEPROP 1 LAST PACK_TYPE C0603
J 0
(-1975 -750);
DISPLAY 0.617021 (-1975 -750);
PAINT SKYBLUE (-1975 -750);
FORCEPROP 1 LAST PATH I17
J 0
(-1975 -400);
DISPLAY 0.978723 (-1975 -400);
PAINT WHITE (-1975 -400);
DISPLAY INVISIBLE (-1975 -400);
FORCEPROP 2 LAST CDS_LIB pure_quanta
J 0
(-2025 -550);
DISPLAY INVISIBLE (-2025 -550);
FORCEADD Q_RES..1
(-1775 -325);
FORCEPROP 1 LAST LOCATION PR837
J 0
(-1825 -275);
DISPLAY 0.617021 (-1825 -275);
PAINT AQUA (-1825 -275);
FORCEPROP 0 LAST $SEC 1
J 0
(-1825 -225);
DISPLAY 0.680851 (-1825 -225);
PAINT MONO (-1825 -225);
DISPLAY INVISIBLE (-1825 -225);
FORCEPROP 0 LAST CDS_SEC 1
J 0
(-1825 -225);
DISPLAY 1.021277 (-1825 -225);
DISPLAY INVISIBLE (-1825 -225);
FORCEPROP 1 LASTPIN (-1875 -325) $PN 1
J 0
(-1863 -313);
DISPLAY 0.617021 (-1863 -313);
PAINT MONO (-1863 -313);
FORCEPROP 1 LASTPIN (-1675 -325) $PN 2
J 0
(-1713 -313);
DISPLAY 0.617021 (-1713 -313);
PAINT MONO (-1713 -313);
FORCEPROP 1 LAST PACK_TYPE 0402LF
J 0
(-1400 -325);
DISPLAY 0.617021 (-1400 -325);
PAINT SKYBLUE (-1400 -325);
FORCEPROP 1 LAST VALUE 1
J 2
(-1625 -325);
DISPLAY 0.617021 (-1625 -325);
PAINT SKYBLUE (-1625 -325);
FORCEPROP 1 LAST TOLERANCE 1%
J 0
(-1650 -275);
DISPLAY 0.617021 (-1650 -275);
PAINT SKYBLUE (-1650 -275);
FORCEPROP 1 LAST WATTAGE 1/16W
J 2
(-1425 -275);
DISPLAY 0.617021 (-1425 -275);
PAINT SKYBLUE (-1425 -275);
FORCEPROP 1 LAST MATERIAL CHIP
J 0
(-1550 -325);
DISPLAY 0.617021 (-1550 -325);
PAINT SKYBLUE (-1550 -325);
FORCEPROP 1 LAST PATH I18
J 0
(-1825 -175);
DISPLAY 0.978723 (-1825 -175);
PAINT WHITE (-1825 -175);
DISPLAY INVISIBLE (-1825 -175);
FORCEPROP 2 LAST CDS_LIB pure_quanta
J 0
(-1775 -325);
DISPLAY INVISIBLE (-1775 -325);
FORCEPROP 1 LAST PART_NUMBER CS-1002FB04
J 0
(-1825 -225);
DISPLAY 0.617021 (-1825 -225);
PAINT BLUE (-1825 -225);
DISPLAY INVISIBLE (-1825 -225);
FORCEADD GND..1
(-1600 -775);
FORCEPROP 3 LASTPIN (-1600 -725) SIG_NAME GND\g
J 0
(-1590 -715);
DISPLAY 0.659574 (-1590 -715);
PAINT MONO (-1590 -715);
DISPLAY INVISIBLE (-1590 -715);
FORCEPROP 1 LAST PATH I19
J 0
(-1525 -775);
DISPLAY 0.872340 (-1525 -775);
PAINT AQUA (-1525 -775);
DISPLAY INVISIBLE (-1525 -775);
FORCEPROP 1 LAST HDL_POWER GND
J 0
(-1600 -625);
DISPLAY 0.872340 (-1600 -625);
PAINT GREEN (-1600 -625);
DISPLAY INVISIBLE (-1600 -625);
FORCEPROP 1 LAST SIZE 1B
J 0
(-1525 -825);
DISPLAY 0.872340 (-1525 -825);
PAINT AQUA (-1525 -825);
DISPLAY INVISIBLE (-1525 -825);
FORCEPROP 2 LAST CDS_LIB pure_quanta_power
J 0
(-1600 -775);
DISPLAY INVISIBLE (-1600 -775);
FORCEADD Q_RES..2
(-3275 -1350);
FORCEPROP 1 LAST $LOCATION R3118
J 0
(-3230 -1225);
DISPLAY 0.787234 (-3230 -1225);
FORCEPROP 0 LAST CDS_LOCATION R3118
J 0
(-3225 -1175);
DISPLAY 1.021277 (-3225 -1175);
DISPLAY INVISIBLE (-3225 -1175);
FORCEPROP 0 LAST $SEC 1
J 0
(-3225 -1175);
DISPLAY 0.680851 (-3225 -1175);
PAINT MONO (-3225 -1175);
DISPLAY INVISIBLE (-3225 -1175);
FORCEPROP 0 LAST CDS_SEC 1
J 0
(-3225 -1175);
DISPLAY 1.021277 (-3225 -1175);
DISPLAY INVISIBLE (-3225 -1175);
FORCEPROP 1 LASTPIN (-3275 -1250) $PN 1
J 0
(-3270 -1288);
DISPLAY 0.787234 (-3270 -1288);
PAINT MONO (-3270 -1288);
FORCEPROP 1 LASTPIN (-3275 -1450) $PN 2
J 0
(-3270 -1440);
DISPLAY 0.787234 (-3270 -1440);
PAINT MONO (-3270 -1440);
FORCEPROP 1 LAST PACK_TYPE 0402LF
J 0
(-3235 -1525);
DISPLAY 0.787234 (-3235 -1525);
FORCEPROP 1 LAST PART_NUMBER CS38662FB05
J 0
(-3235 -1475);
DISPLAY 0.787234 (-3235 -1475);
FORCEPROP 1 LAST VALUE 86.6K
J 0
(-3230 -1275);
DISPLAY 0.787234 (-3230 -1275);
FORCEPROP 1 LAST TOLERANCE 1%
J 0
(-3230 -1325);
DISPLAY 0.787234 (-3230 -1325);
FORCEPROP 1 LAST WATTAGE 1/16W
J 0
(-3235 -1375);
DISPLAY 0.787234 (-3235 -1375);
FORCEPROP 1 LAST MATERIAL EMPTY
J 0
(-3235 -1425);
DISPLAY 0.787234 (-3235 -1425);
PAINT RED (-3235 -1425);
FORCEPROP 1 LAST PATH I2
J 0
(-3225 -1175);
DISPLAY 0.978723 (-3225 -1175);
PAINT WHITE (-3225 -1175);
DISPLAY INVISIBLE (-3225 -1175);
FORCEPROP 2 LAST CDS_LIB pure_quanta
J 0
(-3275 -1350);
DISPLAY INVISIBLE (-3275 -1350);
FORCEADD Q_CAP..1
(-1600 -550);
FORCEPROP 1 LAST LOCATION PC591
J 0
(-1550 -450);
DISPLAY 0.617021 (-1550 -450);
PAINT AQUA (-1550 -450);
FORCEPROP 0 LAST $SEC 1
J 0
(-1550 -400);
DISPLAY 0.680851 (-1550 -400);
PAINT MONO (-1550 -400);
DISPLAY INVISIBLE (-1550 -400);
FORCEPROP 0 LAST CDS_SEC 1
J 0
(-1550 -400);
DISPLAY 1.021277 (-1550 -400);
DISPLAY INVISIBLE (-1550 -400);
FORCEPROP 1 LASTPIN (-1600 -450) $PN 1
J 0
(-1590 -470);
DISPLAY 0.617021 (-1590 -470);
PAINT MONO (-1590 -470);
FORCEPROP 1 LASTPIN (-1600 -650) $PN 2
J 0
(-1590 -670);
DISPLAY 0.617021 (-1590 -670);
PAINT MONO (-1590 -670);
FORCEPROP 1 LAST TOLERANCE 10%
J 0
(-1550 -600);
DISPLAY 0.617021 (-1550 -600);
PAINT SKYBLUE (-1550 -600);
FORCEPROP 1 LAST MATERIAL X6S
J 0
(-1550 -650);
DISPLAY 0.617021 (-1550 -650);
PAINT SKYBLUE (-1550 -650);
FORCEPROP 1 LAST VOLTAGE 16V
J 0
(-1550 -550);
DISPLAY 0.617021 (-1550 -550);
PAINT SKYBLUE (-1550 -550);
FORCEPROP 1 LAST VALUE 2.2UF
J 0
(-1550 -500);
DISPLAY 0.617021 (-1550 -500);
PAINT SKYBLUE (-1550 -500);
FORCEPROP 1 LAST PACK_TYPE C0603
J 0
(-1550 -750);
DISPLAY 0.617021 (-1550 -750);
PAINT SKYBLUE (-1550 -750);
FORCEPROP 1 LAST PART_NUMBER CH5223KE901
J 0
(-1550 -700);
DISPLAY 0.617021 (-1550 -700);
PAINT BLUE (-1550 -700);
FORCEPROP 1 LAST PATH I20
J 0
(-1550 -400);
DISPLAY 0.978723 (-1550 -400);
PAINT WHITE (-1550 -400);
DISPLAY INVISIBLE (-1550 -400);
FORCEPROP 2 LAST CDS_LIB pure_quanta
J 0
(-1600 -550);
DISPLAY INVISIBLE (-1600 -550);
FORCEADD NCP3284AMNTXG..1
(-75 -675);
FORCEPROP 1 LAST LOCATION PU9
J 0
(-375 200);
DISPLAY 0.723404 (-375 200);
PAINT GREEN (-375 200);
FORCEPROP 0 LAST $SEC 1
J 0
(-375 350);
DISPLAY 0.680851 (-375 350);
PAINT MONO (-375 350);
DISPLAY INVISIBLE (-375 350);
FORCEPROP 0 LAST CDS_SEC 1
J 0
(-375 350);
DISPLAY 1.021277 (-375 350);
DISPLAY INVISIBLE (-375 350);
FORCEPROP 0 LASTPIN (325 -1275) $PN 32
J 0
(335 -1265);
DISPLAY 0.680851 (335 -1265);
PAINT MONO (335 -1265);
FORCEPROP 0 LASTPIN (325 -275) $PN 26
J 0
(335 -265);
DISPLAY 0.680851 (335 -265);
PAINT MONO (335 -265);
FORCEPROP 0 LASTPIN (-525 -475) $PN 27
J 2
(-535 -465);
DISPLAY 0.680851 (-535 -465);
PAINT MONO (-535 -465);
FORCEPROP 0 LASTPIN (325 -875) $PN 30
J 0
(335 -865);
DISPLAY 0.680851 (335 -865);
PAINT MONO (335 -865);
FORCEPROP 0 LASTPIN (-525 -625) $PN 6
J 2
(-535 -615);
DISPLAY 0.680851 (-535 -615);
PAINT MONO (-535 -615);
FORCEPROP 0 LASTPIN (-525 -675) $PN 37
J 2
(-535 -665);
DISPLAY 0.680851 (-535 -665);
PAINT MONO (-535 -665);
FORCEPROP 0 LASTPIN (-525 -825) $PN 35
J 2
(-535 -815);
DISPLAY 0.680851 (-535 -815);
PAINT MONO (-535 -815);
FORCEPROP 0 LASTPIN (-525 -1125) $PN 1
J 2
(-535 -1115);
DISPLAY 0.680851 (-535 -1115);
PAINT MONO (-535 -1115);
FORCEPROP 0 LASTPIN (-525 -925) $PN 36
J 2
(-535 -915);
DISPLAY 0.680851 (-535 -915);
PAINT MONO (-535 -915);
FORCEPROP 0 LASTPIN (-525 -1275) $PN 33
J 2
(-535 -1265);
DISPLAY 0.680851 (-535 -1265);
PAINT MONO (-535 -1265);
FORCEPROP 0 LASTPIN (-525 -1325) $PN 34
J 2
(-535 -1315);
DISPLAY 0.680851 (-535 -1315);
PAINT MONO (-535 -1315);
FORCEPROP 0 LASTPIN (325 -1325) $PN 7_10-19
J 0
(335 -1315);
DISPLAY 0.680851 (335 -1315);
PAINT MONO (335 -1315);
FORCEPROP 0 LASTPIN (325 -25) $PN 2
J 0
(335 -15);
DISPLAY 0.680851 (335 -15);
PAINT MONO (335 -15);
FORCEPROP 0 LASTPIN (325 -475) $PN 25
J 0
(335 -465);
DISPLAY 0.680851 (335 -465);
PAINT MONO (335 -465);
FORCEPROP 0 LASTPIN (-525 -75) $PN 20_24
J 2
(-535 -65);
DISPLAY 0.680851 (-535 -65);
PAINT MONO (-535 -65);
FORCEPROP 0 LASTPIN (-525 -1025) $PN 29
J 2
(-535 -1015);
DISPLAY 0.680851 (-535 -1015);
PAINT MONO (-535 -1015);
FORCEPROP 0 LASTPIN (325 -675) $PN 11_18
J 0
(335 -665);
DISPLAY 0.680851 (335 -665);
PAINT MONO (335 -665);
FORCEPROP 0 LASTPIN (-525 -275) $PN 4
J 2
(-535 -265);
DISPLAY 0.680851 (-535 -265);
PAINT MONO (-535 -265);
FORCEPROP 0 LASTPIN (-525 -225) $PN 5
J 2
(-535 -215);
DISPLAY 0.680851 (-535 -215);
PAINT MONO (-535 -215);
FORCEPROP 0 LASTPIN (-525 -25) $PN 3
J 2
(-535 -15);
DISPLAY 0.680851 (-535 -15);
PAINT MONO (-535 -15);
FORCEPROP 0 LASTPIN (325 -1175) $PN 28
J 0
(335 -1165);
DISPLAY 0.680851 (335 -1165);
PAINT MONO (335 -1165);
FORCEPROP 0 LASTPIN (325 -1125) $PN 31
J 0
(335 -1115);
DISPLAY 0.680851 (335 -1115);
PAINT MONO (335 -1115);
FORCEPROP 1 LAST PART_NUMBER AL003284002
J 0
(-375 125);
DISPLAY 0.723404 (-375 125);
PAINT GREEN (-375 125);
FORCEPROP 2 LAST VALUE NCP3284AMNTXG
J 0
(-375 250);
DISPLAY 0.617021 (-375 250);
PAINT SKYBLUE (-375 250);
FORCEPROP 1 LAST MATERIAL IC
J 0
(-375 50);
DISPLAY 0.723404 (-375 50);
PAINT GREEN (-375 50);
FORCEPROP 2 LAST PART_TYPE SMLF
J 0
(-375 300);
DISPLAY 1.021277 (-375 300);
FORCEPROP 1 LAST PATH I21
J 0
(-75 -675);
DISPLAY 0.723404 (-75 -675);
PAINT GREEN (-75 -675);
DISPLAY INVISIBLE (-75 -675);
FORCEPROP 1 LAST CDS_LMAN_SYM_OUTLINE -300,700,250,-700
J 0
(-75 -675);
DISPLAY 0.468085 (-75 -675);
PAINT GREEN (-75 -675);
DISPLAY INVISIBLE (-75 -675);
FORCEPROP 1 LAST NEEDS_NO_SIZE TRUE
J 0
(-75 -675);
DISPLAY 0.723404 (-75 -675);
PAINT GREEN (-75 -675);
DISPLAY INVISIBLE (-75 -675);
FORCEPROP 2 LAST CDS_LIB pure_quanta
J 0
(-75 -675);
DISPLAY INVISIBLE (-75 -675);
FORCEADD GND..1
(-4500 675);
FORCEPROP 3 LASTPIN (-4500 725) SIG_NAME GND\g
J 0
(-4490 735);
DISPLAY 0.659574 (-4490 735);
PAINT MONO (-4490 735);
DISPLAY INVISIBLE (-4490 735);
FORCEPROP 1 LAST PATH I22
J 0
(-4425 675);
DISPLAY 0.872340 (-4425 675);
PAINT AQUA (-4425 675);
DISPLAY INVISIBLE (-4425 675);
FORCEPROP 1 LAST HDL_POWER GND
J 0
(-4500 825);
DISPLAY 0.872340 (-4500 825);
PAINT GREEN (-4500 825);
DISPLAY INVISIBLE (-4500 825);
FORCEPROP 1 LAST SIZE 1B
J 0
(-4425 625);
DISPLAY 0.872340 (-4425 625);
PAINT AQUA (-4425 625);
DISPLAY INVISIBLE (-4425 625);
FORCEPROP 2 LAST CDS_LIB pure_quanta_power
J 0
(-4500 675);
DISPLAY INVISIBLE (-4500 675);
FORCEADD Q_CAP..1
(-4500 925);
FORCEPROP 1 LAST LOCATION PC1649
J 0
(-4450 1025);
DISPLAY 0.787234 (-4450 1025);
FORCEPROP 0 LAST $SEC 1
J 0
(-4450 1075);
DISPLAY 0.680851 (-4450 1075);
PAINT MONO (-4450 1075);
DISPLAY INVISIBLE (-4450 1075);
FORCEPROP 0 LAST CDS_SEC 1
J 0
(-4450 1075);
DISPLAY 1.021277 (-4450 1075);
DISPLAY INVISIBLE (-4450 1075);
FORCEPROP 1 LASTPIN (-4500 1025) $PN 1
J 0
(-4490 1005);
DISPLAY 0.787234 (-4490 1005);
PAINT MONO (-4490 1005);
FORCEPROP 1 LASTPIN (-4500 825) $PN 2
J 0
(-4490 805);
DISPLAY 0.787234 (-4490 805);
PAINT MONO (-4490 805);
FORCEPROP 1 LAST PART_NUMBER CH4106K1B01
J 0
(-4450 775);
DISPLAY 0.787234 (-4450 775);
FORCEPROP 1 LAST VOLTAGE 50V
J 0
(-4450 925);
DISPLAY 0.787234 (-4450 925);
FORCEPROP 1 LAST VALUE 100NF
J 0
(-4450 975);
DISPLAY 0.787234 (-4450 975);
FORCEPROP 1 LAST TOLERANCE 10%
J 0
(-4450 875);
DISPLAY 0.787234 (-4450 875);
FORCEPROP 1 LAST MATERIAL X7R
J 0
(-4450 825);
DISPLAY 0.787234 (-4450 825);
FORCEPROP 1 LAST PACK_TYPE C0402
J 0
(-4450 725);
DISPLAY 0.787234 (-4450 725);
FORCEPROP 1 LAST PATH I23
J 0
(-4450 1075);
DISPLAY 0.978723 (-4450 1075);
PAINT WHITE (-4450 1075);
DISPLAY INVISIBLE (-4450 1075);
FORCEPROP 2 LAST CDS_LIB pure_quanta
J 0
(-4500 925);
DISPLAY INVISIBLE (-4500 925);
FORCEADD UNIVERSAL_POWER..1
(-4500 1550);
FORCEPROP 3 LASTPIN (-4500 1500) SIG_NAME P12V_AUX\g
J 0
(-4490 1510);
DISPLAY 0.659574 (-4490 1510);
PAINT MONO (-4490 1510);
DISPLAY INVISIBLE (-4490 1510);
FORCEPROP 1 LAST HDL_POWER P12V_AUX
J 1
(-4500 1600);
DISPLAY 0.617021 (-4500 1600);
PAINT GREEN (-4500 1600);
FORCEPROP 1 LAST PATH I24
J 0
(-4450 1575);
DISPLAY 0.872340 (-4450 1575);
PAINT AQUA (-4450 1575);
DISPLAY INVISIBLE (-4450 1575);
FORCEPROP 2 LAST CDS_LIB pure_quanta_power
J 0
(-4500 1550);
PAINT MONO (-4500 1550);
DISPLAY INVISIBLE (-4500 1550);
FORCEADD Q_INDUCTOR..1
(-4275 1150);
FORCEPROP 1 LAST LOCATION PL58
J 0
(-4400 1310);
DISPLAY 0.617021 (-4400 1310);
PAINT AQUA (-4400 1310);
FORCEPROP 0 LAST $SEC 1
J 0
(-4400 1450);
DISPLAY 0.680851 (-4400 1450);
PAINT MONO (-4400 1450);
DISPLAY INVISIBLE (-4400 1450);
FORCEPROP 0 LAST CDS_SEC 1
J 0
(-4400 1450);
DISPLAY 1.021277 (-4400 1450);
DISPLAY INVISIBLE (-4400 1450);
FORCEPROP 0 LASTPIN (-4375 1125) $PN 1
J 2
(-4385 1135);
DISPLAY 0.617021 (-4385 1135);
PAINT MONO (-4385 1135);
FORCEPROP 0 LASTPIN (-4175 1125) $PN 2
J 0
(-4165 1135);
DISPLAY 0.617021 (-4165 1135);
PAINT MONO (-4165 1135);
FORCEPROP 1 LAST PART_NUMBER CV+10G0MZ04
J 0
(-4400 1260);
DISPLAY 0.617021 (-4400 1260);
PAINT BLUE (-4400 1260);
FORCEPROP 2 LAST VALUE 100NH/16A
J 0
(-4400 1400);
DISPLAY 0.617021 (-4400 1400);
PAINT SKYBLUE (-4400 1400);
FORCEPROP 1 LAST MATERIAL IND
J 0
(-4400 1205);
DISPLAY 0.617021 (-4400 1205);
PAINT SKYBLUE (-4400 1205);
FORCEPROP 2 LAST PACK_TYPE SMLF
J 0
(-4400 1350);
DISPLAY 0.617021 (-4400 1350);
PAINT SKYBLUE (-4400 1350);
FORCEPROP 1 LAST PATH I25
J 0
(-4200 1205);
DISPLAY 0.723404 (-4200 1205);
PAINT GREEN (-4200 1205);
DISPLAY INVISIBLE (-4200 1205);
FORCEPROP 1 LAST NEEDS_NO_SIZE TRUE
J 0
(-4275 1150);
DISPLAY 0.468085 (-4275 1150);
PAINT GREEN (-4275 1150);
DISPLAY INVISIBLE (-4275 1150);
FORCEPROP 2 LAST CDS_LIB pure_quanta
J 0
(-4275 1150);
DISPLAY INVISIBLE (-4275 1150);
FORCEADD Q_CAP..1
(-4025 275);
FORCEPROP 1 LAST LOCATION PC2260
J 0
(-3975 375);
DISPLAY 0.617021 (-3975 375);
PAINT AQUA (-3975 375);
FORCEPROP 0 LAST $SEC 1
J 0
(-3975 425);
DISPLAY 0.680851 (-3975 425);
PAINT MONO (-3975 425);
DISPLAY INVISIBLE (-3975 425);
FORCEPROP 0 LAST CDS_SEC 1
J 0
(-3975 425);
DISPLAY 1.021277 (-3975 425);
DISPLAY INVISIBLE (-3975 425);
FORCEPROP 1 LASTPIN (-4025 375) $PN 1
J 0
(-4015 355);
DISPLAY 0.787234 (-4015 355);
PAINT MONO (-4015 355);
FORCEPROP 1 LASTPIN (-4025 175) $PN 2
J 0
(-4015 155);
DISPLAY 0.787234 (-4015 155);
PAINT MONO (-4015 155);
FORCEPROP 1 LAST VALUE 22UF
J 0
(-3975 325);
DISPLAY 0.617021 (-3975 325);
PAINT SKYBLUE (-3975 325);
FORCEPROP 1 LAST VOLTAGE 16V
J 0
(-3975 275);
DISPLAY 0.617021 (-3975 275);
PAINT SKYBLUE (-3975 275);
FORCEPROP 1 LAST PART_NUMBER CH6223MEA01
J 0
(-3975 125);
DISPLAY 0.489362 (-3975 125);
PAINT BLUE (-3975 125);
FORCEPROP 1 LAST MATERIAL X6S
J 0
(-3975 175);
DISPLAY 0.617021 (-3975 175);
PAINT SKYBLUE (-3975 175);
FORCEPROP 1 LAST PACK_TYPE C0805
J 0
(-3975 75);
DISPLAY 0.617021 (-3975 75);
PAINT SKYBLUE (-3975 75);
FORCEPROP 1 LAST TOLERANCE 20%
J 0
(-3975 225);
DISPLAY 0.617021 (-3975 225);
PAINT SKYBLUE (-3975 225);
FORCEPROP 1 LAST PATH I26
J 0
(-3975 425);
DISPLAY 0.978723 (-3975 425);
PAINT WHITE (-3975 425);
DISPLAY INVISIBLE (-3975 425);
FORCEPROP 2 LAST CDS_LIB pure_quanta
J 0
(-4025 275);
DISPLAY INVISIBLE (-4025 275);
FORCEADD GND..1
(-3950 550);
FORCEPROP 3 LASTPIN (-3950 600) SIG_NAME GND\g
J 0
(-3940 610);
DISPLAY 0.659574 (-3940 610);
PAINT MONO (-3940 610);
DISPLAY INVISIBLE (-3940 610);
FORCEPROP 1 LAST PATH I27
J 0
(-3875 550);
DISPLAY 0.872340 (-3875 550);
PAINT AQUA (-3875 550);
DISPLAY INVISIBLE (-3875 550);
FORCEPROP 1 LAST HDL_POWER GND
J 0
(-3950 700);
DISPLAY 0.872340 (-3950 700);
PAINT GREEN (-3950 700);
DISPLAY INVISIBLE (-3950 700);
FORCEPROP 2 LAST CDS_LIB pure_quanta_power
J 0
(-3950 550);
PAINT MONO (-3950 550);
DISPLAY INVISIBLE (-3950 550);
FORCEPROP 1 LAST SIZE 1B
J 0
(-3875 500);
DISPLAY 0.872340 (-3875 500);
PAINT AQUA (-3875 500);
DISPLAY INVISIBLE (-3875 500);
FORCEADD Q_CAPP..1
(-3950 925);
FORCEPROP 1 LAST LOCATION PC3
J 0
(-3900 1100);
DISPLAY 1.021277 (-3900 1100);
PAINT AQUA (-3900 1100);
DISPLAY INVISIBLE (-3900 1100);
FORCEPROP 0 LAST $SEC 1
J 0
(-3900 1100);
DISPLAY 0.680851 (-3900 1100);
PAINT MONO (-3900 1100);
DISPLAY INVISIBLE (-3900 1100);
FORCEPROP 0 LAST CDS_SEC 1
J 0
(-3900 1100);
DISPLAY 1.021277 (-3900 1100);
DISPLAY INVISIBLE (-3900 1100);
FORCEPROP 1 LASTPIN (-3950 1025) $PN 1
J 0
(-3940 1010);
DISPLAY 0.787234 (-3940 1010);
PAINT MONO (-3940 1010);
FORCEPROP 1 LASTPIN (-3950 825) $PN 2
J 0
(-3940 810);
DISPLAY 0.787234 (-3940 810);
PAINT MONO (-3940 810);
FORCEPROP 1 LAST MATERIAL OSCON
J 0
(-3900 850);
DISPLAY 0.617021 (-3900 850);
PAINT SKYBLUE (-3900 850);
FORCEPROP 1 LAST PACK_TYPE THLF
J 0
(-3900 800);
DISPLAY 0.617021 (-3900 800);
PAINT SKYBLUE (-3900 800);
FORCEPROP 1 LAST VOLTAGE 16V
J 0
(-3900 900);
DISPLAY 0.617021 (-3900 900);
PAINT SKYBLUE (-3900 900);
FORCEPROP 1 LAST VALUE 270UF
J 0
(-3900 1000);
DISPLAY 0.617021 (-3900 1000);
PAINT SKYBLUE (-3900 1000);
FORCEPROP 1 LAST TOLERANCE 20%
J 0
(-3900 950);
DISPLAY 0.617021 (-3900 950);
PAINT SKYBLUE (-3900 950);
FORCEPROP 1 LAST PART_NUMBER CC72703MD38
J 0
(-3900 750);
DISPLAY 0.489362 (-3900 750);
PAINT BLUE (-3900 750);
FORCEPROP 1 LAST PATH I28
J 0
(-3900 1075);
DISPLAY 0.978723 (-3900 1075);
DISPLAY INVISIBLE (-3900 1075);
FORCEPROP 2 LAST CDS_LIB pure_quanta
J 0
(-3950 925);
DISPLAY INVISIBLE (-3950 925);
FORCEPROP 1 LAST LOCATION PC3
J 0
(-3900 1050);
DISPLAY 0.617021 (-3900 1050);
PAINT AQUA (-3900 1050);
FORCEADD Q_CAP..1
(-3700 275);
FORCEPROP 1 LAST LOCATION PC2261
J 0
(-3650 375);
DISPLAY 0.617021 (-3650 375);
PAINT AQUA (-3650 375);
FORCEPROP 0 LAST $SEC 1
J 0
(-3650 425);
DISPLAY 0.680851 (-3650 425);
PAINT MONO (-3650 425);
DISPLAY INVISIBLE (-3650 425);
FORCEPROP 0 LAST CDS_SEC 1
J 0
(-3650 425);
DISPLAY 1.021277 (-3650 425);
DISPLAY INVISIBLE (-3650 425);
FORCEPROP 1 LASTPIN (-3700 375) $PN 1
J 0
(-3690 355);
DISPLAY 0.787234 (-3690 355);
PAINT MONO (-3690 355);
FORCEPROP 1 LASTPIN (-3700 175) $PN 2
J 0
(-3690 155);
DISPLAY 0.787234 (-3690 155);
PAINT MONO (-3690 155);
FORCEPROP 1 LAST VOLTAGE 16V
J 0
(-3650 275);
DISPLAY 0.617021 (-3650 275);
PAINT SKYBLUE (-3650 275);
FORCEPROP 1 LAST MATERIAL X6S
J 0
(-3650 175);
DISPLAY 0.617021 (-3650 175);
PAINT SKYBLUE (-3650 175);
FORCEPROP 1 LAST VALUE 22UF
J 0
(-3650 325);
DISPLAY 0.617021 (-3650 325);
PAINT SKYBLUE (-3650 325);
FORCEPROP 1 LAST PACK_TYPE C0805
J 0
(-3650 75);
DISPLAY 0.617021 (-3650 75);
PAINT SKYBLUE (-3650 75);
FORCEPROP 1 LAST PART_NUMBER CH6223MEA01
J 0
(-3650 125);
DISPLAY 0.489362 (-3650 125);
PAINT BLUE (-3650 125);
FORCEPROP 1 LAST TOLERANCE 20%
J 0
(-3650 225);
DISPLAY 0.617021 (-3650 225);
PAINT SKYBLUE (-3650 225);
FORCEPROP 1 LAST PATH I29
J 0
(-3650 425);
DISPLAY 0.978723 (-3650 425);
PAINT WHITE (-3650 425);
DISPLAY INVISIBLE (-3650 425);
FORCEPROP 2 LAST CDS_LIB pure_quanta
J 0
(-3700 275);
DISPLAY INVISIBLE (-3700 275);
FORCEADD GND..1
(-4025 -75);
FORCEPROP 3 LASTPIN (-4025 -25) SIG_NAME GND\g
J 0
(-4015 -15);
DISPLAY 0.659574 (-4015 -15);
PAINT MONO (-4015 -15);
DISPLAY INVISIBLE (-4015 -15);
FORCEPROP 1 LAST PATH I3
J 0
(-3950 -75);
DISPLAY 0.872340 (-3950 -75);
PAINT AQUA (-3950 -75);
DISPLAY INVISIBLE (-3950 -75);
FORCEPROP 1 LAST HDL_POWER GND
J 0
(-4025 75);
DISPLAY 0.872340 (-4025 75);
PAINT GREEN (-4025 75);
DISPLAY INVISIBLE (-4025 75);
FORCEPROP 2 LAST CDS_LIB pure_quanta_power
J 0
(-4025 -75);
DISPLAY INVISIBLE (-4025 -75);
FORCEPROP 1 LAST SIZE 1B
J 0
(-3950 -125);
DISPLAY 0.872340 (-3950 -125);
PAINT AQUA (-3950 -125);
DISPLAY INVISIBLE (-3950 -125);
FORCEADD Q_CAP..1
(-3375 275);
FORCEPROP 1 LAST LOCATION PC2262
J 0
(-3325 375);
DISPLAY 0.617021 (-3325 375);
PAINT AQUA (-3325 375);
FORCEPROP 0 LAST $SEC 1
J 0
(-3325 425);
DISPLAY 0.680851 (-3325 425);
PAINT MONO (-3325 425);
DISPLAY INVISIBLE (-3325 425);
FORCEPROP 0 LAST CDS_SEC 1
J 0
(-3325 425);
DISPLAY 1.021277 (-3325 425);
DISPLAY INVISIBLE (-3325 425);
FORCEPROP 1 LASTPIN (-3375 375) $PN 1
J 0
(-3365 355);
DISPLAY 0.787234 (-3365 355);
PAINT MONO (-3365 355);
FORCEPROP 1 LASTPIN (-3375 175) $PN 2
J 0
(-3365 155);
DISPLAY 0.787234 (-3365 155);
PAINT MONO (-3365 155);
FORCEPROP 1 LAST VOLTAGE 16V
J 0
(-3325 275);
DISPLAY 0.617021 (-3325 275);
PAINT SKYBLUE (-3325 275);
FORCEPROP 1 LAST PART_NUMBER CH6223MEA01
J 0
(-3325 125);
DISPLAY 0.489362 (-3325 125);
PAINT BLUE (-3325 125);
FORCEPROP 1 LAST VALUE 22UF
J 0
(-3325 325);
DISPLAY 0.617021 (-3325 325);
PAINT SKYBLUE (-3325 325);
FORCEPROP 1 LAST PACK_TYPE C0805
J 0
(-3325 75);
DISPLAY 0.617021 (-3325 75);
PAINT SKYBLUE (-3325 75);
FORCEPROP 1 LAST TOLERANCE 20%
J 0
(-3325 225);
DISPLAY 0.617021 (-3325 225);
PAINT SKYBLUE (-3325 225);
FORCEPROP 1 LAST MATERIAL X6S
J 0
(-3325 175);
DISPLAY 0.617021 (-3325 175);
PAINT SKYBLUE (-3325 175);
FORCEPROP 1 LAST PATH I30
J 0
(-3325 425);
DISPLAY 0.978723 (-3325 425);
PAINT WHITE (-3325 425);
DISPLAY INVISIBLE (-3325 425);
FORCEPROP 2 LAST CDS_LIB pure_quanta
J 0
(-3375 275);
DISPLAY INVISIBLE (-3375 275);
FORCEADD Q_CAPP..1
(-3650 925);
FORCEPROP 1 LAST LOCATION PC566
J 0
(-3600 1100);
DISPLAY 1.021277 (-3600 1100);
PAINT AQUA (-3600 1100);
DISPLAY INVISIBLE (-3600 1100);
FORCEPROP 0 LAST $SEC 1
J 0
(-3600 1100);
DISPLAY 0.680851 (-3600 1100);
PAINT MONO (-3600 1100);
DISPLAY INVISIBLE (-3600 1100);
FORCEPROP 0 LAST CDS_SEC 1
J 0
(-3600 1100);
DISPLAY 1.021277 (-3600 1100);
DISPLAY INVISIBLE (-3600 1100);
FORCEPROP 1 LASTPIN (-3650 1025) $PN 1
J 0
(-3640 1010);
DISPLAY 0.617021 (-3640 1010);
PAINT MONO (-3640 1010);
FORCEPROP 1 LASTPIN (-3650 825) $PN 2
J 0
(-3640 810);
DISPLAY 0.617021 (-3640 810);
PAINT MONO (-3640 810);
FORCEPROP 1 LAST VOLTAGE 16V
J 0
(-3600 900);
DISPLAY 0.617021 (-3600 900);
PAINT SKYBLUE (-3600 900);
FORCEPROP 1 LAST MATERIAL OSCON
J 0
(-3600 850);
DISPLAY 0.617021 (-3600 850);
PAINT SKYBLUE (-3600 850);
FORCEPROP 1 LAST PART_NUMBER CC72703MD38
J 0
(-3600 750);
DISPLAY 0.489362 (-3600 750);
PAINT BLUE (-3600 750);
FORCEPROP 1 LAST PACK_TYPE THLF
J 0
(-3600 800);
DISPLAY 0.617021 (-3600 800);
PAINT SKYBLUE (-3600 800);
FORCEPROP 1 LAST TOLERANCE 20%
J 0
(-3600 950);
DISPLAY 0.617021 (-3600 950);
PAINT SKYBLUE (-3600 950);
FORCEPROP 1 LAST VALUE 270UF
J 0
(-3600 1000);
DISPLAY 0.617021 (-3600 1000);
PAINT SKYBLUE (-3600 1000);
FORCEPROP 1 LAST PATH I31
J 0
(-3600 1075);
DISPLAY 0.978723 (-3600 1075);
DISPLAY INVISIBLE (-3600 1075);
FORCEPROP 2 LAST CDS_LIB pure_quanta
J 0
(-3650 925);
DISPLAY INVISIBLE (-3650 925);
FORCEPROP 1 LAST LOCATION PC566
J 0
(-3600 1050);
DISPLAY 0.617021 (-3600 1050);
PAINT AQUA (-3600 1050);
FORCEADD Q_CAP..1
(-3325 925);
FORCEPROP 1 LAST LOCATION PC700
J 0
(-3275 1025);
DISPLAY 0.617021 (-3275 1025);
PAINT AQUA (-3275 1025);
FORCEPROP 0 LAST $SEC 1
J 0
(-3275 1075);
DISPLAY 0.680851 (-3275 1075);
PAINT MONO (-3275 1075);
DISPLAY INVISIBLE (-3275 1075);
FORCEPROP 2 LAST CDS_SEC 1
J 0
(-3275 1125);
DISPLAY 1.021277 (-3275 1125);
DISPLAY INVISIBLE (-3275 1125);
FORCEPROP 1 LASTPIN (-3325 1025) $PN 1
J 0
(-3315 1005);
DISPLAY 0.787234 (-3315 1005);
PAINT MONO (-3315 1005);
DISPLAY INVISIBLE (-3315 1005);
FORCEPROP 1 LASTPIN (-3325 825) $PN 2
J 0
(-3315 805);
DISPLAY 0.787234 (-3315 805);
PAINT MONO (-3315 805);
DISPLAY INVISIBLE (-3315 805);
FORCEPROP 1 LAST PART_NUMBER CH6223MEA01
J 0
(-3275 775);
DISPLAY 0.489362 (-3275 775);
PAINT BLUE (-3275 775);
FORCEPROP 1 LAST PACK_TYPE C0805
J 0
(-3275 725);
DISPLAY 0.617021 (-3275 725);
PAINT SKYBLUE (-3275 725);
FORCEPROP 1 LAST VOLTAGE 16V
J 0
(-3275 925);
DISPLAY 0.617021 (-3275 925);
PAINT SKYBLUE (-3275 925);
FORCEPROP 1 LAST TOLERANCE 20%
J 0
(-3275 875);
DISPLAY 0.617021 (-3275 875);
PAINT SKYBLUE (-3275 875);
FORCEPROP 1 LAST MATERIAL X6S
J 0
(-3275 825);
DISPLAY 0.617021 (-3275 825);
PAINT SKYBLUE (-3275 825);
FORCEPROP 1 LAST VALUE 22UF
J 0
(-3275 975);
DISPLAY 0.617021 (-3275 975);
PAINT SKYBLUE (-3275 975);
FORCEPROP 1 LAST PATH I32
J 0
(-3275 1075);
DISPLAY 0.978723 (-3275 1075);
PAINT WHITE (-3275 1075);
DISPLAY INVISIBLE (-3275 1075);
FORCEPROP 2 LAST CDS_LIB pure_quanta
J 0
(-3325 925);
DISPLAY INVISIBLE (-3325 925);
FORCEADD Q_CAP..1
(-3050 275);
FORCEPROP 1 LAST LOCATION PC2263
J 0
(-3000 375);
DISPLAY 0.617021 (-3000 375);
PAINT AQUA (-3000 375);
FORCEPROP 0 LAST $SEC 1
J 0
(-3000 425);
DISPLAY 0.680851 (-3000 425);
PAINT MONO (-3000 425);
DISPLAY INVISIBLE (-3000 425);
FORCEPROP 0 LAST CDS_SEC 1
J 0
(-3000 425);
DISPLAY 1.021277 (-3000 425);
DISPLAY INVISIBLE (-3000 425);
FORCEPROP 1 LASTPIN (-3050 375) $PN 1
J 0
(-3040 355);
DISPLAY 0.787234 (-3040 355);
PAINT MONO (-3040 355);
FORCEPROP 1 LASTPIN (-3050 175) $PN 2
J 0
(-3040 155);
DISPLAY 0.787234 (-3040 155);
PAINT MONO (-3040 155);
FORCEPROP 1 LAST MATERIAL X6S
J 0
(-3000 175);
DISPLAY 0.617021 (-3000 175);
PAINT SKYBLUE (-3000 175);
FORCEPROP 1 LAST PART_NUMBER CH6223MEA01
J 0
(-3000 125);
DISPLAY 0.489362 (-3000 125);
PAINT BLUE (-3000 125);
FORCEPROP 1 LAST PACK_TYPE C0805
J 0
(-3000 75);
DISPLAY 0.617021 (-3000 75);
PAINT SKYBLUE (-3000 75);
FORCEPROP 1 LAST VALUE 22UF
J 0
(-3000 325);
DISPLAY 0.617021 (-3000 325);
PAINT SKYBLUE (-3000 325);
FORCEPROP 1 LAST VOLTAGE 16V
J 0
(-3000 275);
DISPLAY 0.617021 (-3000 275);
PAINT SKYBLUE (-3000 275);
FORCEPROP 1 LAST TOLERANCE 20%
J 0
(-3000 225);
DISPLAY 0.617021 (-3000 225);
PAINT SKYBLUE (-3000 225);
FORCEPROP 1 LAST PATH I33
J 0
(-3000 425);
DISPLAY 0.978723 (-3000 425);
PAINT WHITE (-3000 425);
DISPLAY INVISIBLE (-3000 425);
FORCEPROP 2 LAST CDS_LIB pure_quanta
J 0
(-3050 275);
DISPLAY INVISIBLE (-3050 275);
FORCEADD Q_CAP..1
(-2725 275);
FORCEPROP 1 LAST LOCATION PC2342
J 0
(-2675 375);
DISPLAY 0.617021 (-2675 375);
PAINT AQUA (-2675 375);
FORCEPROP 0 LAST $SEC 1
J 0
(-2675 425);
DISPLAY 0.680851 (-2675 425);
PAINT MONO (-2675 425);
DISPLAY INVISIBLE (-2675 425);
FORCEPROP 0 LAST CDS_SEC 1
J 0
(-2675 425);
DISPLAY 1.021277 (-2675 425);
DISPLAY INVISIBLE (-2675 425);
FORCEPROP 1 LASTPIN (-2725 375) $PN 1
J 0
(-2715 355);
DISPLAY 0.787234 (-2715 355);
PAINT MONO (-2715 355);
FORCEPROP 1 LASTPIN (-2725 175) $PN 2
J 0
(-2715 155);
DISPLAY 0.787234 (-2715 155);
PAINT MONO (-2715 155);
FORCEPROP 1 LAST PART_NUMBER CH6223MEA01
J 0
(-2675 125);
DISPLAY 0.489362 (-2675 125);
PAINT BLUE (-2675 125);
FORCEPROP 1 LAST VALUE 22UF
J 0
(-2675 325);
DISPLAY 0.617021 (-2675 325);
PAINT SKYBLUE (-2675 325);
FORCEPROP 1 LAST PACK_TYPE C0805
J 0
(-2675 75);
DISPLAY 0.617021 (-2675 75);
PAINT SKYBLUE (-2675 75);
FORCEPROP 1 LAST VOLTAGE 16V
J 0
(-2675 275);
DISPLAY 0.617021 (-2675 275);
PAINT SKYBLUE (-2675 275);
FORCEPROP 1 LAST MATERIAL X6S
J 0
(-2675 175);
DISPLAY 0.617021 (-2675 175);
PAINT SKYBLUE (-2675 175);
FORCEPROP 1 LAST TOLERANCE 20%
J 0
(-2675 225);
DISPLAY 0.617021 (-2675 225);
PAINT SKYBLUE (-2675 225);
FORCEPROP 1 LAST PATH I34
J 0
(-2675 425);
DISPLAY 0.978723 (-2675 425);
PAINT WHITE (-2675 425);
DISPLAY INVISIBLE (-2675 425);
FORCEPROP 2 LAST CDS_LIB pure_quanta
J 0
(-2725 275);
DISPLAY INVISIBLE (-2725 275);
FORCEADD Q_CAP..1
(-3000 925);
FORCEPROP 1 LAST LOCATION PC570
J 0
(-2950 1025);
DISPLAY 0.617021 (-2950 1025);
PAINT AQUA (-2950 1025);
FORCEPROP 0 LAST $SEC 1
J 0
(-2950 1075);
DISPLAY 0.680851 (-2950 1075);
PAINT MONO (-2950 1075);
DISPLAY INVISIBLE (-2950 1075);
FORCEPROP 0 LAST CDS_SEC 1
J 0
(-2950 1075);
DISPLAY 1.021277 (-2950 1075);
DISPLAY INVISIBLE (-2950 1075);
FORCEPROP 1 LASTPIN (-3000 1025) $PN 1
J 0
(-2990 1005);
DISPLAY 0.617021 (-2990 1005);
PAINT MONO (-2990 1005);
FORCEPROP 1 LASTPIN (-3000 825) $PN 2
J 0
(-2990 805);
DISPLAY 0.617021 (-2990 805);
PAINT MONO (-2990 805);
FORCEPROP 1 LAST MATERIAL X6S
J 0
(-2950 825);
DISPLAY 0.617021 (-2950 825);
PAINT SKYBLUE (-2950 825);
FORCEPROP 1 LAST PART_NUMBER CH6223MEA01
J 0
(-2950 775);
DISPLAY 0.489362 (-2950 775);
PAINT BLUE (-2950 775);
FORCEPROP 1 LAST TOLERANCE 20%
J 0
(-2950 875);
DISPLAY 0.617021 (-2950 875);
PAINT SKYBLUE (-2950 875);
FORCEPROP 1 LAST PACK_TYPE C0805
J 0
(-2950 725);
DISPLAY 0.617021 (-2950 725);
PAINT SKYBLUE (-2950 725);
FORCEPROP 1 LAST VALUE 22UF
J 0
(-2950 975);
DISPLAY 0.617021 (-2950 975);
PAINT SKYBLUE (-2950 975);
FORCEPROP 1 LAST VOLTAGE 16V
J 0
(-2950 925);
DISPLAY 0.617021 (-2950 925);
PAINT SKYBLUE (-2950 925);
FORCEPROP 1 LAST PATH I35
J 0
(-2950 1075);
DISPLAY 0.978723 (-2950 1075);
PAINT WHITE (-2950 1075);
DISPLAY INVISIBLE (-2950 1075);
FORCEPROP 2 LAST CDS_LIB pure_quanta
J 0
(-3000 925);
DISPLAY INVISIBLE (-3000 925);
FORCEADD Q_CAP..1
(-2400 275);
FORCEPROP 1 LAST LOCATION PC2343
J 0
(-2350 375);
DISPLAY 0.617021 (-2350 375);
PAINT AQUA (-2350 375);
FORCEPROP 0 LAST $SEC 1
J 0
(-2350 425);
DISPLAY 0.680851 (-2350 425);
PAINT MONO (-2350 425);
DISPLAY INVISIBLE (-2350 425);
FORCEPROP 0 LAST CDS_SEC 1
J 0
(-2350 425);
DISPLAY 1.021277 (-2350 425);
DISPLAY INVISIBLE (-2350 425);
FORCEPROP 1 LASTPIN (-2400 375) $PN 1
J 0
(-2390 355);
DISPLAY 0.787234 (-2390 355);
PAINT MONO (-2390 355);
FORCEPROP 1 LASTPIN (-2400 175) $PN 2
J 0
(-2390 155);
DISPLAY 0.787234 (-2390 155);
PAINT MONO (-2390 155);
FORCEPROP 1 LAST PACK_TYPE C0805
J 0
(-2350 75);
DISPLAY 0.617021 (-2350 75);
PAINT SKYBLUE (-2350 75);
FORCEPROP 1 LAST PART_NUMBER CH6223MEA01
J 0
(-2350 125);
DISPLAY 0.489362 (-2350 125);
PAINT BLUE (-2350 125);
FORCEPROP 1 LAST TOLERANCE 20%
J 0
(-2350 225);
DISPLAY 0.617021 (-2350 225);
PAINT SKYBLUE (-2350 225);
FORCEPROP 1 LAST VOLTAGE 16V
J 0
(-2350 275);
DISPLAY 0.617021 (-2350 275);
PAINT SKYBLUE (-2350 275);
FORCEPROP 1 LAST VALUE 22UF
J 0
(-2350 325);
DISPLAY 0.617021 (-2350 325);
PAINT SKYBLUE (-2350 325);
FORCEPROP 1 LAST MATERIAL X6S
J 0
(-2350 175);
DISPLAY 0.617021 (-2350 175);
PAINT SKYBLUE (-2350 175);
FORCEPROP 1 LAST PATH I36
J 0
(-2350 425);
DISPLAY 0.978723 (-2350 425);
PAINT WHITE (-2350 425);
DISPLAY INVISIBLE (-2350 425);
FORCEPROP 2 LAST CDS_LIB pure_quanta
J 0
(-2400 275);
DISPLAY INVISIBLE (-2400 275);
FORCEADD Q_CAP..1
(-2675 925);
FORCEPROP 1 LAST LOCATION PC571
J 0
(-2625 1025);
DISPLAY 0.617021 (-2625 1025);
PAINT AQUA (-2625 1025);
FORCEPROP 0 LAST $SEC 1
J 0
(-2625 1075);
DISPLAY 0.680851 (-2625 1075);
PAINT MONO (-2625 1075);
DISPLAY INVISIBLE (-2625 1075);
FORCEPROP 0 LAST CDS_SEC 1
J 0
(-2625 1075);
DISPLAY 1.021277 (-2625 1075);
DISPLAY INVISIBLE (-2625 1075);
FORCEPROP 1 LASTPIN (-2675 1025) $PN 1
J 0
(-2665 1005);
DISPLAY 0.617021 (-2665 1005);
PAINT MONO (-2665 1005);
FORCEPROP 1 LASTPIN (-2675 825) $PN 2
J 0
(-2665 805);
DISPLAY 0.617021 (-2665 805);
PAINT MONO (-2665 805);
FORCEPROP 1 LAST MATERIAL X6S
J 0
(-2625 825);
DISPLAY 0.617021 (-2625 825);
PAINT SKYBLUE (-2625 825);
FORCEPROP 1 LAST VALUE 22UF
J 0
(-2625 975);
DISPLAY 0.617021 (-2625 975);
PAINT SKYBLUE (-2625 975);
FORCEPROP 1 LAST VOLTAGE 16V
J 0
(-2625 925);
DISPLAY 0.617021 (-2625 925);
PAINT SKYBLUE (-2625 925);
FORCEPROP 1 LAST PART_NUMBER CH6223MEA01
J 0
(-2625 775);
DISPLAY 0.489362 (-2625 775);
PAINT BLUE (-2625 775);
FORCEPROP 1 LAST TOLERANCE 20%
J 0
(-2625 875);
DISPLAY 0.617021 (-2625 875);
PAINT SKYBLUE (-2625 875);
FORCEPROP 1 LAST PACK_TYPE C0805
J 0
(-2625 725);
DISPLAY 0.617021 (-2625 725);
PAINT SKYBLUE (-2625 725);
FORCEPROP 1 LAST PATH I37
J 0
(-2625 1075);
DISPLAY 0.978723 (-2625 1075);
PAINT WHITE (-2625 1075);
DISPLAY INVISIBLE (-2625 1075);
FORCEPROP 2 LAST CDS_LIB pure_quanta
J 0
(-2675 925);
DISPLAY INVISIBLE (-2675 925);
FORCEADD Q_CAP..1
(-2350 925);
FORCEPROP 1 LAST LOCATION PC576
J 0
(-2300 1025);
DISPLAY 0.617021 (-2300 1025);
PAINT AQUA (-2300 1025);
FORCEPROP 0 LAST $SEC 1
J 0
(-2300 1075);
DISPLAY 0.680851 (-2300 1075);
PAINT MONO (-2300 1075);
DISPLAY INVISIBLE (-2300 1075);
FORCEPROP 0 LAST CDS_SEC 1
J 0
(-2300 1075);
DISPLAY 1.021277 (-2300 1075);
DISPLAY INVISIBLE (-2300 1075);
FORCEPROP 1 LASTPIN (-2350 1025) $PN 1
J 0
(-2340 1005);
DISPLAY 0.617021 (-2340 1005);
PAINT MONO (-2340 1005);
FORCEPROP 1 LASTPIN (-2350 825) $PN 2
J 0
(-2340 805);
DISPLAY 0.617021 (-2340 805);
PAINT MONO (-2340 805);
FORCEPROP 1 LAST MATERIAL X6S
J 0
(-2300 825);
DISPLAY 0.617021 (-2300 825);
PAINT SKYBLUE (-2300 825);
FORCEPROP 1 LAST VALUE 22UF
J 0
(-2300 975);
DISPLAY 0.617021 (-2300 975);
PAINT SKYBLUE (-2300 975);
FORCEPROP 1 LAST PACK_TYPE C0805
J 0
(-2300 725);
DISPLAY 0.617021 (-2300 725);
PAINT SKYBLUE (-2300 725);
FORCEPROP 1 LAST PART_NUMBER CH6223MEA01
J 0
(-2300 775);
DISPLAY 0.489362 (-2300 775);
PAINT BLUE (-2300 775);
FORCEPROP 1 LAST VOLTAGE 16V
J 0
(-2300 925);
DISPLAY 0.617021 (-2300 925);
PAINT SKYBLUE (-2300 925);
FORCEPROP 1 LAST TOLERANCE 20%
J 0
(-2300 875);
DISPLAY 0.617021 (-2300 875);
PAINT SKYBLUE (-2300 875);
FORCEPROP 1 LAST PATH I38
J 0
(-2300 1075);
DISPLAY 0.978723 (-2300 1075);
PAINT WHITE (-2300 1075);
DISPLAY INVISIBLE (-2300 1075);
FORCEPROP 2 LAST CDS_LIB pure_quanta
J 0
(-2350 925);
DISPLAY INVISIBLE (-2350 925);
FORCEADD Q_CAP..1
(-2075 275);
FORCEPROP 1 LAST LOCATION PC2344
J 0
(-2025 375);
DISPLAY 0.617021 (-2025 375);
PAINT AQUA (-2025 375);
FORCEPROP 0 LAST $SEC 1
J 0
(-2025 425);
DISPLAY 0.680851 (-2025 425);
PAINT MONO (-2025 425);
DISPLAY INVISIBLE (-2025 425);
FORCEPROP 0 LAST CDS_SEC 1
J 0
(-2025 425);
DISPLAY 1.021277 (-2025 425);
DISPLAY INVISIBLE (-2025 425);
FORCEPROP 1 LASTPIN (-2075 375) $PN 1
J 0
(-2065 355);
DISPLAY 0.787234 (-2065 355);
PAINT MONO (-2065 355);
FORCEPROP 1 LASTPIN (-2075 175) $PN 2
J 0
(-2065 155);
DISPLAY 0.787234 (-2065 155);
PAINT MONO (-2065 155);
FORCEPROP 1 LAST PACK_TYPE C0805
J 0
(-2025 75);
DISPLAY 0.617021 (-2025 75);
PAINT SKYBLUE (-2025 75);
FORCEPROP 1 LAST PART_NUMBER CH6223MEA01
J 0
(-2025 125);
DISPLAY 0.489362 (-2025 125);
PAINT BLUE (-2025 125);
FORCEPROP 1 LAST MATERIAL X6S
J 0
(-2025 175);
DISPLAY 0.617021 (-2025 175);
PAINT SKYBLUE (-2025 175);
FORCEPROP 1 LAST TOLERANCE 20%
J 0
(-2025 225);
DISPLAY 0.617021 (-2025 225);
PAINT SKYBLUE (-2025 225);
FORCEPROP 1 LAST VOLTAGE 16V
J 0
(-2025 275);
DISPLAY 0.617021 (-2025 275);
PAINT SKYBLUE (-2025 275);
FORCEPROP 1 LAST VALUE 22UF
J 0
(-2025 325);
DISPLAY 0.617021 (-2025 325);
PAINT SKYBLUE (-2025 325);
FORCEPROP 1 LAST PATH I39
J 0
(-2025 425);
DISPLAY 0.978723 (-2025 425);
PAINT WHITE (-2025 425);
DISPLAY INVISIBLE (-2025 425);
FORCEPROP 2 LAST CDS_LIB pure_quanta
J 0
(-2075 275);
DISPLAY INVISIBLE (-2075 275);
FORCEADD Q_RES..2
(-3275 -775);
FORCEPROP 1 LAST $LOCATION R3117
J 0
(-3230 -650);
DISPLAY 0.787234 (-3230 -650);
FORCEPROP 0 LAST CDS_LOCATION R3117
J 0
(-3225 -600);
DISPLAY 1.021277 (-3225 -600);
DISPLAY INVISIBLE (-3225 -600);
FORCEPROP 0 LAST $SEC 1
J 0
(-3225 -600);
DISPLAY 0.680851 (-3225 -600);
PAINT MONO (-3225 -600);
DISPLAY INVISIBLE (-3225 -600);
FORCEPROP 0 LAST CDS_SEC 1
J 0
(-3225 -600);
DISPLAY 1.021277 (-3225 -600);
DISPLAY INVISIBLE (-3225 -600);
FORCEPROP 1 LASTPIN (-3275 -675) $PN 1
J 0
(-3270 -713);
DISPLAY 0.787234 (-3270 -713);
PAINT MONO (-3270 -713);
FORCEPROP 1 LASTPIN (-3275 -875) $PN 2
J 0
(-3270 -865);
DISPLAY 0.787234 (-3270 -865);
PAINT MONO (-3270 -865);
FORCEPROP 1 LAST TOLERANCE 5%
J 0
(-3230 -750);
DISPLAY 0.787234 (-3230 -750);
FORCEPROP 1 LAST PART_NUMBER CS45102JB03
J 0
(-3235 -900);
DISPLAY 0.787234 (-3235 -900);
FORCEPROP 1 LAST MATERIAL EMPTY
J 0
(-3235 -850);
DISPLAY 0.787234 (-3235 -850);
PAINT RED (-3235 -850);
FORCEPROP 1 LAST WATTAGE 1/16W
J 0
(-3235 -800);
DISPLAY 0.787234 (-3235 -800);
FORCEPROP 1 LAST VALUE 510K
J 0
(-3230 -700);
DISPLAY 0.787234 (-3230 -700);
FORCEPROP 1 LAST PACK_TYPE 0402LF
J 0
(-3235 -950);
DISPLAY 0.787234 (-3235 -950);
FORCEPROP 1 LAST PATH I4
J 0
(-3225 -600);
DISPLAY 0.978723 (-3225 -600);
PAINT WHITE (-3225 -600);
DISPLAY INVISIBLE (-3225 -600);
FORCEPROP 2 LAST CDS_LIB pure_quanta
J 0
(-3275 -775);
DISPLAY INVISIBLE (-3275 -775);
FORCEADD Q_CAP..1
(-2025 925);
FORCEPROP 1 LAST LOCATION PC701
J 0
(-1975 1025);
DISPLAY 0.617021 (-1975 1025);
PAINT AQUA (-1975 1025);
FORCEPROP 0 LAST $SEC 1
J 0
(-1975 1075);
DISPLAY 0.680851 (-1975 1075);
PAINT MONO (-1975 1075);
DISPLAY INVISIBLE (-1975 1075);
FORCEPROP 0 LAST CDS_SEC 1
J 0
(-1975 1075);
DISPLAY 1.021277 (-1975 1075);
DISPLAY INVISIBLE (-1975 1075);
FORCEPROP 1 LASTPIN (-2025 1025) $PN 1
J 0
(-2015 1005);
DISPLAY 0.617021 (-2015 1005);
PAINT MONO (-2015 1005);
FORCEPROP 1 LASTPIN (-2025 825) $PN 2
J 0
(-2015 805);
DISPLAY 0.617021 (-2015 805);
PAINT MONO (-2015 805);
FORCEPROP 1 LAST VALUE 22UF
J 0
(-1975 975);
DISPLAY 0.617021 (-1975 975);
PAINT SKYBLUE (-1975 975);
FORCEPROP 1 LAST VOLTAGE 16V
J 0
(-1975 925);
DISPLAY 0.617021 (-1975 925);
PAINT SKYBLUE (-1975 925);
FORCEPROP 1 LAST MATERIAL X6S
J 0
(-1975 825);
DISPLAY 0.617021 (-1975 825);
PAINT SKYBLUE (-1975 825);
FORCEPROP 1 LAST TOLERANCE 20%
J 0
(-1975 875);
DISPLAY 0.617021 (-1975 875);
PAINT SKYBLUE (-1975 875);
FORCEPROP 1 LAST PART_NUMBER CH6223MEA01
J 0
(-1975 775);
DISPLAY 0.489362 (-1975 775);
PAINT BLUE (-1975 775);
FORCEPROP 1 LAST PACK_TYPE C0805
J 0
(-1975 725);
DISPLAY 0.617021 (-1975 725);
PAINT SKYBLUE (-1975 725);
FORCEPROP 1 LAST PATH I40
J 0
(-1975 1075);
DISPLAY 0.978723 (-1975 1075);
PAINT WHITE (-1975 1075);
DISPLAY INVISIBLE (-1975 1075);
FORCEPROP 2 LAST CDS_LIB pure_quanta
J 0
(-2025 925);
DISPLAY INVISIBLE (-2025 925);
FORCEADD Q_CAP..1
(-1700 925);
FORCEPROP 1 LAST LOCATION PC577
J 0
(-1650 1025);
DISPLAY 0.617021 (-1650 1025);
PAINT AQUA (-1650 1025);
FORCEPROP 0 LAST $SEC 1
J 0
(-1650 1075);
DISPLAY 0.680851 (-1650 1075);
PAINT MONO (-1650 1075);
DISPLAY INVISIBLE (-1650 1075);
FORCEPROP 0 LAST CDS_SEC 1
J 0
(-1650 1075);
DISPLAY 1.021277 (-1650 1075);
DISPLAY INVISIBLE (-1650 1075);
FORCEPROP 1 LASTPIN (-1700 1025) $PN 1
J 0
(-1690 1005);
DISPLAY 0.617021 (-1690 1005);
PAINT MONO (-1690 1005);
FORCEPROP 1 LASTPIN (-1700 825) $PN 2
J 0
(-1690 805);
DISPLAY 0.617021 (-1690 805);
PAINT MONO (-1690 805);
FORCEPROP 1 LAST TOLERANCE 10%
J 0
(-1650 875);
DISPLAY 0.617021 (-1650 875);
PAINT SKYBLUE (-1650 875);
FORCEPROP 1 LAST VALUE 0.1UF
J 0
(-1650 975);
DISPLAY 0.617021 (-1650 975);
PAINT SKYBLUE (-1650 975);
FORCEPROP 1 LAST MATERIAL X7R
J 0
(-1650 825);
DISPLAY 0.617021 (-1650 825);
PAINT SKYBLUE (-1650 825);
FORCEPROP 1 LAST VOLTAGE 25V
J 0
(-1650 925);
DISPLAY 0.617021 (-1650 925);
PAINT SKYBLUE (-1650 925);
FORCEPROP 1 LAST PART_NUMBER CH4104K1B00
J 0
(-1650 775);
DISPLAY 0.489362 (-1650 775);
PAINT BLUE (-1650 775);
FORCEPROP 1 LAST PACK_TYPE 0402
J 0
(-1650 725);
DISPLAY 0.617021 (-1650 725);
PAINT SKYBLUE (-1650 725);
FORCEPROP 1 LAST PATH I41
J 0
(-1650 1075);
DISPLAY 0.978723 (-1650 1075);
PAINT WHITE (-1650 1075);
DISPLAY INVISIBLE (-1650 1075);
FORCEPROP 2 LAST CDS_LIB pure_quanta
J 0
(-1700 925);
DISPLAY INVISIBLE (-1700 925);
FORCEADD GND..1
(-875 275);
FORCEPROP 3 LASTPIN (-875 325) SIG_NAME GND\g
J 0
(-865 335);
DISPLAY 0.659574 (-865 335);
PAINT MONO (-865 335);
DISPLAY INVISIBLE (-865 335);
FORCEPROP 1 LAST PATH I42
J 0
(-800 275);
DISPLAY 0.872340 (-800 275);
PAINT AQUA (-800 275);
DISPLAY INVISIBLE (-800 275);
FORCEPROP 1 LAST HDL_POWER GND
J 0
(-875 425);
DISPLAY 0.872340 (-875 425);
PAINT GREEN (-875 425);
DISPLAY INVISIBLE (-875 425);
FORCEPROP 1 LAST SIZE 1B
J 0
(-800 225);
DISPLAY 0.872340 (-800 225);
PAINT AQUA (-800 225);
DISPLAY INVISIBLE (-800 225);
FORCEPROP 2 LAST CDS_LIB pure_quanta_power
J 0
(-875 275);
DISPLAY INVISIBLE (-875 275);
FORCEADD Q_CAP..1
(-875 550);
FORCEPROP 1 LAST LOCATION PC702
J 0
(-825 650);
DISPLAY 0.617021 (-825 650);
PAINT AQUA (-825 650);
FORCEPROP 0 LAST $SEC 1
J 0
(-825 700);
DISPLAY 0.680851 (-825 700);
PAINT MONO (-825 700);
DISPLAY INVISIBLE (-825 700);
FORCEPROP 0 LAST CDS_SEC 1
J 0
(-825 700);
DISPLAY 1.021277 (-825 700);
DISPLAY INVISIBLE (-825 700);
FORCEPROP 1 LASTPIN (-875 650) $PN 1
J 0
(-865 630);
DISPLAY 0.787234 (-865 630);
PAINT MONO (-865 630);
FORCEPROP 1 LASTPIN (-875 450) $PN 2
J 0
(-865 430);
DISPLAY 0.787234 (-865 430);
PAINT MONO (-865 430);
FORCEPROP 1 LAST VOLTAGE 16V
J 0
(-825 550);
DISPLAY 0.617021 (-825 550);
PAINT SKYBLUE (-825 550);
FORCEPROP 1 LAST VALUE 1UF
J 0
(-825 600);
DISPLAY 0.617021 (-825 600);
PAINT SKYBLUE (-825 600);
FORCEPROP 1 LAST TOLERANCE 10%
J 0
(-825 500);
DISPLAY 0.617021 (-825 500);
PAINT SKYBLUE (-825 500);
FORCEPROP 1 LAST MATERIAL X7R
J 0
(-825 450);
DISPLAY 0.617021 (-825 450);
PAINT SKYBLUE (-825 450);
FORCEPROP 1 LAST PART_NUMBER TMP_QCH5103K1900
J 0
(-825 400);
DISPLAY 0.489362 (-825 400);
PAINT BLUE (-825 400);
FORCEPROP 1 LAST PACK_TYPE 0603
J 0
(-825 350);
DISPLAY 0.617021 (-825 350);
PAINT SKYBLUE (-825 350);
FORCEPROP 1 LAST PATH I43
J 0
(-825 700);
DISPLAY 0.978723 (-825 700);
PAINT WHITE (-825 700);
DISPLAY INVISIBLE (-825 700);
FORCEPROP 2 LAST CDS_LIB pure_quanta
J 0
(-875 550);
DISPLAY INVISIBLE (-875 550);
FORCEADD UNIVERSAL_POWER..1
(-1125 875);
FORCEPROP 3 LASTPIN (-1125 825) SIG_NAME P12V_AUX\g
J 0
(-1115 835);
DISPLAY 0.659574 (-1115 835);
PAINT MONO (-1115 835);
DISPLAY INVISIBLE (-1115 835);
FORCEPROP 1 LAST HDL_POWER P12V_AUX
J 1
(-1125 925);
DISPLAY 0.617021 (-1125 925);
PAINT GREEN (-1125 925);
FORCEPROP 1 LAST PATH I44
J 0
(-1075 900);
DISPLAY 0.872340 (-1075 900);
PAINT AQUA (-1075 900);
DISPLAY INVISIBLE (-1075 900);
FORCEPROP 2 LAST CDS_LIB pure_quanta_power
J 0
(-1125 875);
DISPLAY INVISIBLE (-1125 875);
FORCEADD GND..1
(375 -1425);
FORCEPROP 3 LASTPIN (375 -1375) SIG_NAME GND\g
J 0
(385 -1365);
DISPLAY 0.659574 (385 -1365);
PAINT MONO (385 -1365);
DISPLAY INVISIBLE (385 -1365);
FORCEPROP 1 LAST PATH I45
J 0
(450 -1425);
DISPLAY 0.872340 (450 -1425);
PAINT AQUA (450 -1425);
DISPLAY INVISIBLE (450 -1425);
FORCEPROP 1 LAST HDL_POWER GND
J 0
(375 -1275);
DISPLAY 0.872340 (375 -1275);
PAINT GREEN (375 -1275);
DISPLAY INVISIBLE (375 -1275);
FORCEPROP 2 LAST CDS_LIB pure_quanta_power
J 0
(375 -1425);
DISPLAY INVISIBLE (375 -1425);
FORCEPROP 1 LAST SIZE 1B
J 0
(450 -1475);
DISPLAY 0.872340 (450 -1475);
PAINT AQUA (450 -1475);
DISPLAY INVISIBLE (450 -1475);
FORCEADD GND..1
R 1
(575 -1125);
FORCEPROP 3 LASTPIN (525 -1125) SIG_NAME GND\g
J 0
(535 -1115);
DISPLAY 0.659574 (535 -1115);
PAINT MONO (535 -1115);
DISPLAY INVISIBLE (535 -1115);
FORCEPROP 1 LAST PATH I46
R 1
J 0
(575 -1050);
DISPLAY 0.872340 (575 -1050);
PAINT AQUA (575 -1050);
DISPLAY INVISIBLE (575 -1050);
FORCEPROP 1 LAST HDL_POWER GND
R 1
J 0
(425 -1125);
DISPLAY 0.872340 (425 -1125);
PAINT GREEN (425 -1125);
DISPLAY INVISIBLE (425 -1125);
FORCEPROP 2 LAST CDS_LIB pure_quanta_power
R 1
J 0
(575 -1125);
DISPLAY INVISIBLE (575 -1125);
FORCEPROP 1 LAST SIZE 1B
R 1
J 0
(625 -1050);
DISPLAY 0.872340 (625 -1050);
PAINT AQUA (625 -1050);
DISPLAY INVISIBLE (625 -1050);
FORCEADD Q_RES..1
(850 -1175);
FORCEPROP 1 LAST LOCATION PR836
J 0
(800 -1125);
DISPLAY 0.617021 (800 -1125);
PAINT AQUA (800 -1125);
FORCEPROP 0 LAST $SEC 1
J 0
(800 -1075);
DISPLAY 0.680851 (800 -1075);
PAINT MONO (800 -1075);
DISPLAY INVISIBLE (800 -1075);
FORCEPROP 0 LAST CDS_SEC 1
J 0
(800 -1075);
DISPLAY 1.021277 (800 -1075);
DISPLAY INVISIBLE (800 -1075);
FORCEPROP 1 LASTPIN (750 -1175) $PN 1
J 0
(762 -1163);
DISPLAY 0.617021 (762 -1163);
PAINT MONO (762 -1163);
FORCEPROP 1 LASTPIN (950 -1175) $PN 2
J 0
(912 -1163);
DISPLAY 0.617021 (912 -1163);
PAINT MONO (912 -1163);
FORCEPROP 1 LAST PACK_TYPE 0402LF
J 0
(925 -1275);
DISPLAY 0.617021 (925 -1275);
PAINT SKYBLUE (925 -1275);
FORCEPROP 1 LAST TOLERANCE 1%
J 0
(850 -1275);
DISPLAY 0.617021 (850 -1275);
PAINT SKYBLUE (850 -1275);
FORCEPROP 1 LAST MATERIAL CHIP
J 0
(850 -1325);
DISPLAY 0.617021 (850 -1325);
PAINT SKYBLUE (850 -1325);
FORCEPROP 1 LAST PART_NUMBER CS21002FB06
J 0
(700 -1400);
DISPLAY 0.617021 (700 -1400);
PAINT BLUE (700 -1400);
FORCEPROP 1 LAST WATTAGE 1/16W
J 2
(825 -1325);
DISPLAY 0.617021 (825 -1325);
PAINT SKYBLUE (825 -1325);
FORCEPROP 1 LAST VALUE 1K
J 2
(825 -1275);
DISPLAY 0.617021 (825 -1275);
PAINT SKYBLUE (825 -1275);
FORCEPROP 1 LAST PATH I47
J 0
(800 -1025);
DISPLAY 0.978723 (800 -1025);
PAINT WHITE (800 -1025);
DISPLAY INVISIBLE (800 -1025);
FORCEPROP 2 LAST CDS_LIB pure_quanta
J 0
(850 -1175);
DISPLAY INVISIBLE (850 -1175);
FORCEADD Q_CAP..2
(750 -475);
FORCEPROP 1 LAST LOCATION PC568
J 1
(750 -550);
DISPLAY 0.617021 (750 -550);
PAINT AQUA (750 -550);
FORCEPROP 0 LAST $SEC 1
J 0
(1000 -475);
DISPLAY 0.680851 (1000 -475);
PAINT MONO (1000 -475);
DISPLAY INVISIBLE (1000 -475);
FORCEPROP 2 LAST CDS_SEC 1
J 0
(750 -225);
DISPLAY 1.021277 (750 -225);
DISPLAY INVISIBLE (750 -225);
FORCEPROP 1 LASTPIN (650 -475) $PN 1
J 0
(640 -460);
DISPLAY 0.617021 (640 -460);
PAINT MONO (640 -460);
FORCEPROP 1 LASTPIN (850 -475) $PN 2
J 0
(835 -460);
DISPLAY 0.617021 (835 -460);
PAINT MONO (835 -460);
FORCEPROP 1 LAST TOLERANCE 10%
J 2
(1000 -575);
DISPLAY 0.617021 (1000 -575);
PAINT SKYBLUE (1000 -575);
FORCEPROP 1 LAST VALUE 0.22UF
J 2
(1000 -525);
DISPLAY 0.617021 (1000 -525);
PAINT SKYBLUE (1000 -525);
FORCEPROP 1 LAST MATERIAL X7R
J 0
(1000 -575);
DISPLAY 0.617021 (1000 -575);
PAINT SKYBLUE (1000 -575);
FORCEPROP 1 LAST VOLTAGE 25V
J 0
(1000 -525);
DISPLAY 0.617021 (1000 -525);
PAINT SKYBLUE (1000 -525);
FORCEPROP 1 LAST PATH I48
J 0
(750 -275);
DISPLAY 0.978723 (750 -275);
PAINT WHITE (750 -275);
DISPLAY INVISIBLE (750 -275);
FORCEPROP 2 LAST CDS_LIB pure_quanta
J 0
(750 -475);
DISPLAY INVISIBLE (750 -475);
FORCEPROP 1 LAST PART_NUMBER CH4224K1B01
J 1
(825 -600);
DISPLAY 0.617021 (825 -600);
PAINT BLUE (825 -600);
DISPLAY INVISIBLE (825 -600);
FORCEPROP 1 LAST PACK_TYPE C0402
J 1
(1000 -625);
DISPLAY 0.617021 (1000 -625);
PAINT SKYBLUE (1000 -625);
DISPLAY INVISIBLE (1000 -625);
FORCEADD Q_RES..1
(825 -275);
FORCEPROP 1 LAST LOCATION PR835
J 0
(600 -275);
DISPLAY 0.617021 (600 -275);
PAINT AQUA (600 -275);
FORCEPROP 0 LAST $SEC 1
J 0
(875 -275);
DISPLAY 0.680851 (875 -275);
PAINT MONO (875 -275);
DISPLAY INVISIBLE (875 -275);
FORCEPROP 0 LAST CDS_SEC 1
J 0
(875 -275);
DISPLAY 1.021277 (875 -275);
DISPLAY INVISIBLE (875 -275);
FORCEPROP 1 LASTPIN (725 -275) $PN 1
J 0
(737 -263);
DISPLAY 0.617021 (737 -263);
PAINT MONO (737 -263);
FORCEPROP 1 LASTPIN (925 -275) $PN 2
J 0
(887 -263);
DISPLAY 0.617021 (887 -263);
PAINT MONO (887 -263);
FORCEPROP 1 LAST PACK_TYPE 0402LF
J 0
(875 -325);
DISPLAY 0.617021 (875 -325);
PAINT SKYBLUE (875 -325);
FORCEPROP 1 LAST MATERIAL CHIP
J 0
(800 -375);
DISPLAY 0.617021 (800 -375);
PAINT SKYBLUE (800 -375);
FORCEPROP 1 LAST WATTAGE 1/16W
J 2
(775 -375);
DISPLAY 0.617021 (775 -375);
PAINT SKYBLUE (775 -375);
FORCEPROP 1 LAST TOLERANCE 5%
J 0
(800 -325);
DISPLAY 0.617021 (800 -325);
PAINT SKYBLUE (800 -325);
FORCEPROP 1 LAST VALUE 0
J 2
(775 -325);
DISPLAY 0.617021 (775 -325);
PAINT SKYBLUE (775 -325);
FORCEPROP 1 LAST PATH I49
J 0
(775 -125);
DISPLAY 0.978723 (775 -125);
PAINT WHITE (775 -125);
DISPLAY INVISIBLE (775 -125);
FORCEPROP 1 LAST PART_NUMBER CS00002JB13
J 0
(525 -325);
DISPLAY 0.617021 (525 -325);
PAINT BLUE (525 -325);
DISPLAY INVISIBLE (525 -325);
FORCEPROP 2 LAST CDS_LIB pure_quanta
J 0
(825 -275);
DISPLAY INVISIBLE (825 -275);
FORCEADD OFFPAGE..1
(-3350 -275);
FORCEPROP 2 LAST $XR0 301 
J 0
(-3602 -275);
DISPLAY 0.638298 (-3602 -275);
PAINT MONO (-3602 -275);
FORCEPROP 2 LAST $XR1 214 
J 0
(-3722 -275);
DISPLAY 0.638298 (-3722 -275);
PAINT MONO (-3722 -275);
FORCEPROP 2 LAST $XR2 247 
J 0
(-3842 -275);
DISPLAY 0.638298 (-3842 -275);
PAINT MONO (-3842 -275);
FORCEPROP 2 LAST PATH I5
J 0
(-3600 -225);
DISPLAY 1.021277 (-3600 -225);
DISPLAY INVISIBLE (-3600 -225);
FORCEPROP 1 LAST COMMENT_BODY TRUE
J 0
(-3225 -375);
DISPLAY 0.872340 (-3225 -375);
PAINT GREEN (-3225 -375);
DISPLAY INVISIBLE (-3225 -375);
FORCEPROP 1 LAST OFFPAGE TRUE
J 0
(-3025 -400);
DISPLAY 0.872340 (-3025 -400);
PAINT GREEN (-3025 -400);
DISPLAY INVISIBLE (-3025 -400);
FORCEPROP 2 LAST CDS_LIB standard
J 0
(-3350 -275);
DISPLAY INVISIBLE (-3350 -275);
FORCEADD GND..1
(1225 -1925);
FORCEPROP 3 LASTPIN (1225 -1875) SIG_NAME GND\g
J 0
(1235 -1865);
DISPLAY 0.659574 (1235 -1865);
PAINT MONO (1235 -1865);
DISPLAY INVISIBLE (1235 -1865);
FORCEPROP 1 LAST PATH I50
J 0
(1300 -1925);
DISPLAY 0.872340 (1300 -1925);
PAINT AQUA (1300 -1925);
DISPLAY INVISIBLE (1300 -1925);
FORCEPROP 1 LAST HDL_POWER GND
J 0
(1225 -1775);
DISPLAY 0.872340 (1225 -1775);
PAINT GREEN (1225 -1775);
DISPLAY INVISIBLE (1225 -1775);
FORCEPROP 1 LAST SIZE 1B
J 0
(1300 -1975);
DISPLAY 0.872340 (1300 -1975);
PAINT AQUA (1300 -1975);
DISPLAY INVISIBLE (1300 -1975);
FORCEPROP 2 LAST CDS_LIB pure_quanta_power
J 0
(1225 -1925);
PAINT MONO (1225 -1925);
DISPLAY INVISIBLE (1225 -1925);
FORCEADD Q_RES..2
(1225 -1650);
FORCEPROP 1 LAST LOCATION PR830
J 0
(1275 -1525);
DISPLAY 0.617021 (1275 -1525);
PAINT AQUA (1275 -1525);
FORCEPROP 0 LAST $SEC 1
J 0
(1275 -1475);
DISPLAY 0.680851 (1275 -1475);
PAINT MONO (1275 -1475);
DISPLAY INVISIBLE (1275 -1475);
FORCEPROP 2 LAST CDS_SEC 1
J 0
(1275 -1425);
DISPLAY 1.021277 (1275 -1425);
DISPLAY INVISIBLE (1275 -1425);
FORCEPROP 1 LASTPIN (1225 -1550) $PN 1
J 0
(1230 -1588);
DISPLAY 0.617021 (1230 -1588);
PAINT MONO (1230 -1588);
FORCEPROP 1 LASTPIN (1225 -1750) $PN 2
J 0
(1230 -1740);
DISPLAY 0.617021 (1230 -1740);
PAINT MONO (1230 -1740);
FORCEPROP 1 LAST PACK_TYPE 0402LF
J 0
(1270 -1825);
DISPLAY 0.489362 (1270 -1825);
PAINT SKYBLUE (1270 -1825);
FORCEPROP 1 LAST WATTAGE 1/16W
J 0
(1270 -1675);
DISPLAY 0.489362 (1270 -1675);
PAINT SKYBLUE (1270 -1675);
FORCEPROP 1 LAST TOLERANCE 0.1%
J 0
(1275 -1625);
DISPLAY 0.489362 (1275 -1625);
PAINT SKYBLUE (1275 -1625);
FORCEPROP 1 LAST VALUE 15K
J 0
(1275 -1575);
DISPLAY 0.489362 (1275 -1575);
PAINT SKYBLUE (1275 -1575);
FORCEPROP 1 LAST MATERIAL CHIP
J 0
(1270 -1725);
DISPLAY 0.489362 (1270 -1725);
PAINT SKYBLUE (1270 -1725);
FORCEPROP 1 LAST PART_NUMBER CS31502BB03
J 0
(1270 -1775);
DISPLAY 0.489362 (1270 -1775);
PAINT BLUE (1270 -1775);
FORCEPROP 1 LAST PATH I51
J 0
(1275 -1475);
DISPLAY 0.978723 (1275 -1475);
PAINT WHITE (1275 -1475);
DISPLAY INVISIBLE (1275 -1475);
FORCEPROP 2 LAST CDS_LIB pure_quanta
J 0
(1225 -1650);
DISPLAY INVISIBLE (1225 -1650);
FORCEADD UNIVERSAL_POWER..1
(1100 -1075);
FORCEPROP 3 LASTPIN (1100 -1125) SIG_NAME P3V3_AUX\g
J 0
(1110 -1115);
DISPLAY 0.659574 (1110 -1115);
PAINT MONO (1110 -1115);
DISPLAY INVISIBLE (1110 -1115);
FORCEPROP 1 LAST HDL_POWER P3V3_AUX
J 1
(1100 -1025);
DISPLAY 0.617021 (1100 -1025);
PAINT GREEN (1100 -1025);
FORCEPROP 1 LAST PATH I52
J 0
(1150 -1050);
DISPLAY 0.872340 (1150 -1050);
PAINT AQUA (1150 -1050);
DISPLAY INVISIBLE (1150 -1050);
FORCEPROP 2 LAST CDS_LIB pure_quanta_power
J 0
(1100 -1075);
DISPLAY INVISIBLE (1100 -1075);
FORCEADD Q_INDUCTOR..1
(1450 -650);
FORCEPROP 1 LAST LOCATION PL73
J 0
(1325 -490);
DISPLAY 0.617021 (1325 -490);
PAINT AQUA (1325 -490);
FORCEPROP 0 LAST $SEC 1
J 0
(1325 -350);
DISPLAY 0.680851 (1325 -350);
PAINT MONO (1325 -350);
DISPLAY INVISIBLE (1325 -350);
FORCEPROP 2 LAST CDS_SEC 1
J 0
(1325 -350);
DISPLAY 1.021277 (1325 -350);
DISPLAY INVISIBLE (1325 -350);
FORCEPROP 0 LASTPIN (1350 -675) $PN 1
J 2
(1340 -665);
DISPLAY 0.617021 (1340 -665);
PAINT MONO (1340 -665);
FORCEPROP 0 LASTPIN (1550 -675) $PN 2
J 0
(1560 -665);
DISPLAY 0.617021 (1560 -665);
PAINT MONO (1560 -665);
FORCEPROP 1 LAST PART_NUMBER CV-15^0MZ02
J 0
(1325 -540);
DISPLAY 0.617021 (1325 -540);
PAINT BLUE (1325 -540);
FORCEPROP 1 LAST MATERIAL IND
J 0
(1325 -595);
DISPLAY 0.617021 (1325 -595);
PAINT SKYBLUE (1325 -595);
FORCEPROP 2 LAST PACK_TYPE SMLF
J 0
(1325 -400);
DISPLAY 0.617021 (1325 -400);
PAINT SKYBLUE (1325 -400);
FORCEPROP 2 LAST VALUE 1.5UH/53A
J 0
(1325 -450);
DISPLAY 0.617021 (1325 -450);
PAINT SKYBLUE (1325 -450);
FORCEPROP 2 LAST CDS_LIB pure_quanta
J 0
(1450 -650);
DISPLAY INVISIBLE (1450 -650);
FORCEPROP 1 LAST NEEDS_NO_SIZE TRUE
J 0
(1450 -650);
DISPLAY 0.468085 (1450 -650);
PAINT GREEN (1450 -650);
DISPLAY INVISIBLE (1450 -650);
FORCEPROP 1 LAST PATH I53
J 0
(1525 -595);
DISPLAY 0.723404 (1525 -595);
PAINT GREEN (1525 -595);
DISPLAY INVISIBLE (1525 -595);
FORCEADD OFFPAGE..2
(1425 -25);
FORCEPROP 2 LAST $XR0 222 
J 0
(1614 -25);
DISPLAY 0.638298 (1614 -25);
PAINT MONO (1614 -25);
FORCEPROP 2 LAST $XR1 244 
J 0
(1734 -25);
DISPLAY 0.638298 (1734 -25);
PAINT MONO (1734 -25);
FORCEPROP 2 LAST $XR2 258 
J 0
(1854 -25);
DISPLAY 0.638298 (1854 -25);
PAINT MONO (1854 -25);
FORCEPROP 2 LAST PATH I54
J 0
(1875 25);
DISPLAY 1.021277 (1875 25);
DISPLAY INVISIBLE (1875 25);
FORCEPROP 1 LAST COMMENT_BODY TRUE
J 0
(1380 -120);
DISPLAY 0.872340 (1380 -120);
PAINT GREEN (1380 -120);
DISPLAY INVISIBLE (1380 -120);
FORCEPROP 1 LAST OFFPAGE TRUE
J 0
(1750 -150);
DISPLAY 0.872340 (1750 -150);
PAINT GREEN (1750 -150);
DISPLAY INVISIBLE (1750 -150);
FORCEPROP 2 LAST CDS_LIB standard
J 0
(1425 -25);
PAINT MONO (1425 -25);
DISPLAY INVISIBLE (1425 -25);
FORCEADD Q_CAPP..1
(1675 -900);
FORCEPROP 1 LAST LOCATION PC1866
J 0
(1725 -800);
DISPLAY 0.638298 (1725 -800);
FORCEPROP 0 LAST $SEC 1
J 0
(1725 -750);
DISPLAY 0.680851 (1725 -750);
PAINT MONO (1725 -750);
DISPLAY INVISIBLE (1725 -750);
FORCEPROP 2 LAST CDS_SEC 1
J 0
(1725 -700);
DISPLAY 1.021277 (1725 -700);
DISPLAY INVISIBLE (1725 -700);
FORCEPROP 1 LASTPIN (1675 -800) $PN 1
J 0
(1685 -815);
DISPLAY 0.787234 (1685 -815);
PAINT MONO (1685 -815);
FORCEPROP 1 LASTPIN (1675 -1000) $PN 2
J 0
(1685 -1015);
DISPLAY 0.787234 (1685 -1015);
PAINT MONO (1685 -1015);
FORCEPROP 1 LAST PART_NUMBER CC75601MD16
J 0
(1725 -1100);
DISPLAY 0.638298 (1725 -1100);
FORCEPROP 1 LAST MATERIAL OSCON
J 0
(1725 -1000);
DISPLAY 0.638298 (1725 -1000);
FORCEPROP 1 LAST VOLTAGE 6.3V
J 0
(1725 -950);
DISPLAY 0.638298 (1725 -950);
FORCEPROP 1 LAST VALUE 560UF
J 0
(1725 -850);
DISPLAY 0.638298 (1725 -850);
FORCEPROP 1 LAST TOLERANCE 20%
J 0
(1725 -900);
DISPLAY 0.638298 (1725 -900);
FORCEPROP 1 LAST PACK_TYPE THLF
J 0
(1725 -1050);
DISPLAY 0.638298 (1725 -1050);
FORCEPROP 1 LAST PATH I55
J 0
(1725 -750);
DISPLAY 0.978723 (1725 -750);
DISPLAY INVISIBLE (1725 -750);
FORCEPROP 2 LAST CDS_LIB pure_quanta
J 0
(1675 -900);
DISPLAY INVISIBLE (1675 -900);
FORCEADD Q_CAP..2
(2125 -1775);
FORCEPROP 1 LAST LOCATION PC569
J 1
(1950 -1775);
DISPLAY 0.617021 (1950 -1775);
PAINT AQUA (1950 -1775);
FORCEPROP 0 LAST $SEC 1
J 0
(2125 -1825);
DISPLAY 0.680851 (2125 -1825);
PAINT MONO (2125 -1825);
DISPLAY INVISIBLE (2125 -1825);
FORCEPROP 2 LAST CDS_SEC 1
J 0
(2125 -1525);
DISPLAY 1.021277 (2125 -1525);
DISPLAY INVISIBLE (2125 -1525);
FORCEPROP 1 LASTPIN (2025 -1775) $PN 1
J 0
(2015 -1760);
DISPLAY 0.617021 (2015 -1760);
PAINT MONO (2015 -1760);
FORCEPROP 1 LASTPIN (2225 -1775) $PN 2
J 0
(2210 -1760);
DISPLAY 0.617021 (2210 -1760);
PAINT MONO (2210 -1760);
FORCEPROP 1 LAST VALUE 10PF
J 2
(2350 -1775);
DISPLAY 0.489362 (2350 -1775);
PAINT SKYBLUE (2350 -1775);
FORCEPROP 1 LAST TOLERANCE 1%
J 2
(2425 -1775);
DISPLAY 0.489362 (2425 -1775);
PAINT SKYBLUE (2425 -1775);
FORCEPROP 1 LAST MATERIAL NPO
J 0
(2450 -1775);
DISPLAY 0.489362 (2450 -1775);
PAINT SKYBLUE (2450 -1775);
FORCEPROP 1 LAST PART_NUMBER TMP_QCH0106F0B00
J 1
(2150 -1700);
DISPLAY 0.489362 (2150 -1700);
PAINT BLUE (2150 -1700);
FORCEPROP 1 LAST PACK_TYPE 0402
J 1
(2075 -1625);
DISPLAY 0.382979 (2075 -1625);
PAINT SKYBLUE (2075 -1625);
FORCEPROP 1 LAST VOLTAGE 50V
J 0
(2175 -1625);
DISPLAY 0.382979 (2175 -1625);
PAINT SKYBLUE (2175 -1625);
FORCEPROP 1 LAST PATH I56
J 0
(2125 -1575);
DISPLAY 0.978723 (2125 -1575);
PAINT WHITE (2125 -1575);
DISPLAY INVISIBLE (2125 -1575);
FORCEPROP 2 LAST CDS_LIB pure_quanta
J 0
(2125 -1775);
DISPLAY INVISIBLE (2125 -1775);
FORCEADD Q_RES..1
(2125 -1475);
FORCEPROP 1 LAST LOCATION PR831
J 0
(2075 -1425);
DISPLAY 0.638298 (2075 -1425);
FORCEPROP 0 LAST $SEC 1
J 0
(2075 -1325);
DISPLAY 0.680851 (2075 -1325);
PAINT MONO (2075 -1325);
DISPLAY INVISIBLE (2075 -1325);
FORCEPROP 2 LAST CDS_SEC 1
J 0
(2075 -1275);
DISPLAY 1.021277 (2075 -1275);
DISPLAY INVISIBLE (2075 -1275);
FORCEPROP 1 LASTPIN (2025 -1475) $PN 1
J 0
(2037 -1463);
DISPLAY 0.787234 (2037 -1463);
PAINT MONO (2037 -1463);
DISPLAY INVISIBLE (2037 -1463);
FORCEPROP 1 LASTPIN (2225 -1475) $PN 2
J 0
(2187 -1463);
DISPLAY 0.787234 (2187 -1463);
PAINT MONO (2187 -1463);
DISPLAY INVISIBLE (2187 -1463);
FORCEPROP 1 LAST PART_NUMBER CS34702BB05
J 0
(2250 -1450);
DISPLAY 0.638298 (2250 -1450);
FORCEPROP 1 LAST WATTAGE 1/16W
J 2
(2100 -1600);
DISPLAY 0.638298 (2100 -1600);
FORCEPROP 1 LAST VALUE 47K
J 2
(2100 -1550);
DISPLAY 0.638298 (2100 -1550);
FORCEPROP 1 LAST TOLERANCE 0.1%
J 0
(2125 -1550);
DISPLAY 0.638298 (2125 -1550);
FORCEPROP 1 LAST MATERIAL CHIP
J 0
(2125 -1600);
DISPLAY 0.638298 (2125 -1600);
FORCEPROP 1 LAST PACK_TYPE 0402LF
J 0
(2350 -1550);
DISPLAY 0.638298 (2350 -1550);
FORCEPROP 1 LAST PATH I57
J 0
(2075 -1325);
DISPLAY 0.978723 (2075 -1325);
PAINT WHITE (2075 -1325);
DISPLAY INVISIBLE (2075 -1325);
FORCEPROP 2 LAST CDS_LIB pure_quanta
J 0
(2125 -1475);
DISPLAY INVISIBLE (2125 -1475);
FORCEADD Q_CAPP..1
(2125 -900);
FORCEPROP 1 LAST LOCATION PC1867
J 0
(2175 -800);
DISPLAY 0.638298 (2175 -800);
FORCEPROP 0 LAST $SEC 1
J 0
(2175 -750);
DISPLAY 0.680851 (2175 -750);
PAINT MONO (2175 -750);
DISPLAY INVISIBLE (2175 -750);
FORCEPROP 0 LAST CDS_SEC 1
J 0
(2175 -750);
DISPLAY 1.021277 (2175 -750);
DISPLAY INVISIBLE (2175 -750);
FORCEPROP 1 LASTPIN (2125 -800) $PN 1
J 0
(2135 -815);
DISPLAY 0.787234 (2135 -815);
PAINT MONO (2135 -815);
FORCEPROP 1 LASTPIN (2125 -1000) $PN 2
J 0
(2135 -1015);
DISPLAY 0.787234 (2135 -1015);
PAINT MONO (2135 -1015);
FORCEPROP 1 LAST PACK_TYPE THLF
J 0
(2175 -1050);
DISPLAY 0.638298 (2175 -1050);
FORCEPROP 1 LAST TOLERANCE 20%
J 0
(2175 -900);
DISPLAY 0.638298 (2175 -900);
FORCEPROP 1 LAST VALUE 560UF
J 0
(2175 -850);
DISPLAY 0.638298 (2175 -850);
FORCEPROP 1 LAST VOLTAGE 6.3V
J 0
(2175 -950);
DISPLAY 0.638298 (2175 -950);
FORCEPROP 1 LAST MATERIAL OSCON
J 0
(2175 -1000);
DISPLAY 0.638298 (2175 -1000);
FORCEPROP 1 LAST PART_NUMBER CC75601MD16
J 0
(2175 -1100);
DISPLAY 0.638298 (2175 -1100);
FORCEPROP 1 LAST PATH I58
J 0
(2175 -750);
DISPLAY 0.978723 (2175 -750);
DISPLAY INVISIBLE (2175 -750);
FORCEPROP 2 LAST CDS_LIB pure_quanta
J 0
(2125 -900);
DISPLAY INVISIBLE (2125 -900);
FORCEADD Q_CAP..1
(2575 -875);
FORCEPROP 1 LAST LOCATION PC1868
J 0
(2650 -800);
DISPLAY 0.617021 (2650 -800);
PAINT AQUA (2650 -800);
FORCEPROP 0 LAST $SEC 1
J 0
(2625 -725);
DISPLAY 0.680851 (2625 -725);
PAINT MONO (2625 -725);
DISPLAY INVISIBLE (2625 -725);
FORCEPROP 0 LAST CDS_SEC 1
J 0
(2625 -725);
DISPLAY 0.680851 (2625 -725);
DISPLAY INVISIBLE (2625 -725);
FORCEPROP 1 LASTPIN (2575 -775) $PN 1
J 0
(2585 -795);
DISPLAY 0.617021 (2585 -795);
PAINT MONO (2585 -795);
FORCEPROP 1 LASTPIN (2575 -975) $PN 2
J 0
(2585 -995);
DISPLAY 0.617021 (2585 -995);
PAINT MONO (2585 -995);
FORCEPROP 1 LAST PART_NUMBER CH6222MEA01
J 0
(2650 -1050);
DISPLAY 0.617021 (2650 -1050);
PAINT BLUE (2650 -1050);
FORCEPROP 1 LAST MATERIAL X6S
J 0
(2650 -1000);
DISPLAY 0.617021 (2650 -1000);
PAINT SKYBLUE (2650 -1000);
FORCEPROP 1 LAST VOLTAGE 10V
J 0
(2650 -900);
DISPLAY 0.617021 (2650 -900);
PAINT SKYBLUE (2650 -900);
FORCEPROP 1 LAST TOLERANCE 20%
J 0
(2650 -950);
DISPLAY 0.617021 (2650 -950);
PAINT SKYBLUE (2650 -950);
FORCEPROP 1 LAST PACK_TYPE C0805
J 0
(2650 -1100);
DISPLAY 0.617021 (2650 -1100);
PAINT SKYBLUE (2650 -1100);
FORCEPROP 1 LAST VALUE 22UF
J 0
(2650 -850);
DISPLAY 0.617021 (2650 -850);
PAINT SKYBLUE (2650 -850);
FORCEPROP 1 LAST PATH I59
J 0
(2625 -725);
DISPLAY 0.978723 (2625 -725);
PAINT WHITE (2625 -725);
DISPLAY INVISIBLE (2625 -725);
FORCEPROP 2 LAST CDS_LIB pure_quanta
J 0
(2575 -875);
DISPLAY INVISIBLE (2575 -875);
FORCEADD P1V0_AUX..1
(-3275 -450);
FORCEPROP 3 LASTPIN (-3275 -500) SIG_NAME P12V_AUX\g
J 0
(-3265 -490);
DISPLAY 0.659574 (-3265 -490);
PAINT MONO (-3265 -490);
DISPLAY INVISIBLE (-3265 -490);
FORCEPROP 2 LAST ROOM VR_DDR1_POWER_STAGE
J 0
(-3275 -350);
DISPLAY 0.978723 (-3275 -350);
FORCEPROP 1 LAST HDL_POWER P12V_AUX
J 1
(-3264 -403);
DISPLAY 0.617021 (-3264 -403);
PAINT GREEN (-3264 -403);
FORCEPROP 1 LAST PATH I6
J 0
(-3225 -425);
DISPLAY 0.872340 (-3225 -425);
PAINT AQUA (-3225 -425);
DISPLAY INVISIBLE (-3225 -425);
FORCEPROP 2 LAST CDS_LIB pure_quanta_power
J 0
(-3275 -450);
DISPLAY INVISIBLE (-3275 -450);
FORCEADD GND..1
(3750 -1275);
FORCEPROP 3 LASTPIN (3750 -1225) SIG_NAME GND\g
J 0
(3760 -1215);
DISPLAY 0.659574 (3760 -1215);
PAINT MONO (3760 -1215);
DISPLAY INVISIBLE (3760 -1215);
FORCEPROP 1 LAST PATH I60
J 0
(3825 -1275);
DISPLAY 0.872340 (3825 -1275);
PAINT AQUA (3825 -1275);
DISPLAY INVISIBLE (3825 -1275);
FORCEPROP 1 LAST HDL_POWER GND
J 0
(3750 -1125);
DISPLAY 0.872340 (3750 -1125);
PAINT GREEN (3750 -1125);
DISPLAY INVISIBLE (3750 -1125);
FORCEPROP 1 LAST SIZE 1B
J 0
(3825 -1325);
DISPLAY 0.872340 (3825 -1325);
PAINT AQUA (3825 -1325);
DISPLAY INVISIBLE (3825 -1325);
FORCEPROP 2 LAST CDS_LIB pure_quanta_power
J 0
(3750 -1275);
PAINT MONO (3750 -1275);
DISPLAY INVISIBLE (3750 -1275);
FORCEADD Q_CAP..1
(2975 -900);
FORCEPROP 1 LAST LOCATION PC1599
J 0
(3025 -800);
DISPLAY 0.574468 (3025 -800);
PAINT AQUA (3025 -800);
FORCEPROP 0 LAST $SEC 1
J 0
(3025 -750);
DISPLAY 0.680851 (3025 -750);
PAINT MONO (3025 -750);
DISPLAY INVISIBLE (3025 -750);
FORCEPROP 0 LAST CDS_SEC 1
J 0
(3025 -750);
DISPLAY 1.021277 (3025 -750);
DISPLAY INVISIBLE (3025 -750);
FORCEPROP 1 LASTPIN (2975 -800) $PN 1
J 0
(2985 -820);
DISPLAY 0.617021 (2985 -820);
PAINT MONO (2985 -820);
FORCEPROP 1 LASTPIN (2975 -1000) $PN 2
J 0
(2985 -1020);
DISPLAY 0.617021 (2985 -1020);
PAINT MONO (2985 -1020);
FORCEPROP 1 LAST VOLTAGE 10V
J 0
(3025 -900);
DISPLAY 0.617021 (3025 -900);
PAINT SKYBLUE (3025 -900);
FORCEPROP 1 LAST VALUE 22UF
J 0
(3025 -850);
DISPLAY 0.617021 (3025 -850);
PAINT SKYBLUE (3025 -850);
FORCEPROP 1 LAST TOLERANCE 20%
J 0
(3025 -950);
DISPLAY 0.617021 (3025 -950);
PAINT SKYBLUE (3025 -950);
FORCEPROP 1 LAST MATERIAL X6S
J 0
(3025 -1000);
DISPLAY 0.617021 (3025 -1000);
PAINT SKYBLUE (3025 -1000);
FORCEPROP 1 LAST PART_NUMBER CH6222MEA01
J 0
(3025 -1050);
DISPLAY 0.617021 (3025 -1050);
PAINT BLUE (3025 -1050);
FORCEPROP 1 LAST PACK_TYPE C0805
J 0
(3025 -1100);
DISPLAY 0.617021 (3025 -1100);
PAINT SKYBLUE (3025 -1100);
FORCEPROP 1 LAST PATH I61
J 0
(3025 -750);
DISPLAY 0.978723 (3025 -750);
PAINT WHITE (3025 -750);
DISPLAY INVISIBLE (3025 -750);
FORCEPROP 2 LAST CDS_LIB pure_quanta
J 0
(2975 -900);
DISPLAY INVISIBLE (2975 -900);
FORCEADD Q_CAP..1
(3350 -900);
FORCEPROP 1 LAST LOCATION PC1600
J 0
(3400 -800);
DISPLAY 0.574468 (3400 -800);
PAINT AQUA (3400 -800);
FORCEPROP 0 LAST $SEC 1
J 0
(3400 -750);
DISPLAY 0.680851 (3400 -750);
PAINT MONO (3400 -750);
DISPLAY INVISIBLE (3400 -750);
FORCEPROP 0 LAST CDS_SEC 1
J 0
(3400 -750);
DISPLAY 1.021277 (3400 -750);
DISPLAY INVISIBLE (3400 -750);
FORCEPROP 1 LASTPIN (3350 -800) $PN 1
J 0
(3360 -820);
DISPLAY 0.617021 (3360 -820);
PAINT MONO (3360 -820);
FORCEPROP 1 LASTPIN (3350 -1000) $PN 2
J 0
(3360 -1020);
DISPLAY 0.617021 (3360 -1020);
PAINT MONO (3360 -1020);
FORCEPROP 1 LAST VOLTAGE 10V
J 0
(3400 -900);
DISPLAY 0.617021 (3400 -900);
PAINT SKYBLUE (3400 -900);
FORCEPROP 1 LAST TOLERANCE 20%
J 0
(3400 -950);
DISPLAY 0.617021 (3400 -950);
PAINT SKYBLUE (3400 -950);
FORCEPROP 1 LAST MATERIAL X6S
J 0
(3400 -1000);
DISPLAY 0.617021 (3400 -1000);
PAINT SKYBLUE (3400 -1000);
FORCEPROP 1 LAST PART_NUMBER CH6222MEA01
J 0
(3400 -1050);
DISPLAY 0.617021 (3400 -1050);
PAINT BLUE (3400 -1050);
FORCEPROP 1 LAST PACK_TYPE C0805
J 0
(3400 -1100);
DISPLAY 0.617021 (3400 -1100);
PAINT SKYBLUE (3400 -1100);
FORCEPROP 1 LAST VALUE 22UF
J 0
(3400 -850);
DISPLAY 0.617021 (3400 -850);
PAINT SKYBLUE (3400 -850);
FORCEPROP 1 LAST PATH I62
J 0
(3400 -750);
DISPLAY 0.978723 (3400 -750);
PAINT WHITE (3400 -750);
DISPLAY INVISIBLE (3400 -750);
FORCEPROP 2 LAST CDS_LIB pure_quanta
J 0
(3350 -900);
DISPLAY INVISIBLE (3350 -900);
FORCEADD Q_CAP..1
(3750 -900);
FORCEPROP 1 LAST LOCATION PC1869
J 0
(3800 -800);
DISPLAY 0.617021 (3800 -800);
PAINT AQUA (3800 -800);
FORCEPROP 2 LAST $SEC 1
J 0
(3800 -700);
DISPLAY 0.680851 (3800 -700);
PAINT MONO (3800 -700);
DISPLAY INVISIBLE (3800 -700);
FORCEPROP 2 LAST CDS_SEC 1
J 0
(3800 -700);
DISPLAY 1.021277 (3800 -700);
DISPLAY INVISIBLE (3800 -700);
FORCEPROP 1 LASTPIN (3750 -800) $PN 1
J 0
(3760 -820);
DISPLAY 0.617021 (3760 -820);
FORCEPROP 1 LASTPIN (3750 -1000) $PN 2
J 0
(3760 -1020);
DISPLAY 0.617021 (3760 -1020);
FORCEPROP 1 LAST TOLERANCE 10%
J 0
(3800 -950);
DISPLAY 0.617021 (3800 -950);
PAINT SKYBLUE (3800 -950);
FORCEPROP 1 LAST PART_NUMBER CH4104K1B00
J 0
(3800 -1050);
DISPLAY 0.617021 (3800 -1050);
PAINT BLUE (3800 -1050);
FORCEPROP 1 LAST PACK_TYPE 0402
J 0
(3800 -1100);
DISPLAY 0.617021 (3800 -1100);
PAINT SKYBLUE (3800 -1100);
FORCEPROP 1 LAST VALUE 0.1UF
J 0
(3800 -850);
DISPLAY 0.617021 (3800 -850);
PAINT SKYBLUE (3800 -850);
FORCEPROP 1 LAST MATERIAL X7R
J 0
(3800 -1000);
DISPLAY 0.617021 (3800 -1000);
PAINT SKYBLUE (3800 -1000);
FORCEPROP 1 LAST VOLTAGE 25V
J 0
(3800 -900);
DISPLAY 0.617021 (3800 -900);
PAINT SKYBLUE (3800 -900);
FORCEPROP 1 LAST PATH I63
J 0
(3800 -750);
DISPLAY 0.978723 (3800 -750);
PAINT WHITE (3800 -750);
DISPLAY INVISIBLE (3800 -750);
FORCEPROP 2 LAST CDS_LIB pure_quanta
J 0
(3750 -900);
PAINT MONO (3750 -900);
DISPLAY INVISIBLE (3750 -900);
FORCEADD UNIVERSAL_POWER..1
(4200 -375);
FORCEPROP 3 LASTPIN (4200 -425) SIG_NAME P3V3_AUX\g
J 0
(4210 -415);
DISPLAY 0.659574 (4210 -415);
PAINT MONO (4210 -415);
DISPLAY INVISIBLE (4210 -415);
FORCEPROP 1 LAST HDL_POWER P3V3_AUX
J 1
(4200 -325);
DISPLAY 0.617021 (4200 -325);
PAINT GREEN (4200 -325);
FORCEPROP 1 LAST PATH I64
J 0
(4250 -350);
DISPLAY 0.872340 (4250 -350);
PAINT AQUA (4250 -350);
DISPLAY INVISIBLE (4250 -350);
FORCEPROP 2 LAST CDS_LIB pure_quanta_power
J 0
(4200 -375);
PAINT MONO (4200 -375);
DISPLAY INVISIBLE (4200 -375);
FORCEADD Q_RES..2
(925 275);
FORCEPROP 1 LAST LOCATION PR700
J 0
(970 400);
DISPLAY 0.617021 (970 400);
PAINT AQUA (970 400);
FORCEPROP 2 LAST $SEC 1
J 0
(975 500);
DISPLAY 0.680851 (975 500);
PAINT MONO (975 500);
DISPLAY INVISIBLE (975 500);
FORCEPROP 2 LAST CDS_SEC 1
J 0
(975 500);
DISPLAY 1.021277 (975 500);
DISPLAY INVISIBLE (975 500);
FORCEPROP 1 LASTPIN (925 375) $PN 1
J 0
(930 337);
DISPLAY 0.617021 (930 337);
FORCEPROP 1 LASTPIN (925 175) $PN 2
J 0
(930 185);
DISPLAY 0.617021 (930 185);
FORCEPROP 1 LAST PART_NUMBER CS31002FB08
J 0
(965 100);
DISPLAY 0.617021 (965 100);
PAINT BLUE (965 100);
FORCEPROP 1 LAST PACK_TYPE 0402LF
J 0
(965 150);
DISPLAY 0.617021 (965 150);
PAINT SKYBLUE (965 150);
FORCEPROP 1 LAST MATERIAL CHIP
J 0
(965 200);
DISPLAY 0.617021 (965 200);
PAINT SKYBLUE (965 200);
FORCEPROP 1 LAST WATTAGE 1/16W
J 0
(965 250);
DISPLAY 0.617021 (965 250);
PAINT SKYBLUE (965 250);
FORCEPROP 1 LAST VALUE 10K
J 0
(970 350);
DISPLAY 0.617021 (970 350);
PAINT SKYBLUE (970 350);
FORCEPROP 1 LAST TOLERANCE 1%
J 0
(970 300);
DISPLAY 0.617021 (970 300);
PAINT SKYBLUE (970 300);
FORCEPROP 1 LAST PATH I65
J 0
(975 450);
DISPLAY 0.978723 (975 450);
PAINT WHITE (975 450);
DISPLAY INVISIBLE (975 450);
FORCEPROP 2 LAST CDS_LIB pure_quanta
J 0
(925 275);
PAINT MONO (925 275);
DISPLAY INVISIBLE (925 275);
FORCEADD UNIVERSAL_POWER..1
(925 500);
FORCEPROP 3 LASTPIN (925 450) SIG_NAME P3V3_AUX\g
J 0
(935 460);
DISPLAY 0.659574 (935 460);
PAINT MONO (935 460);
DISPLAY INVISIBLE (935 460);
FORCEPROP 1 LAST HDL_POWER P3V3_AUX
J 1
(925 550);
DISPLAY 0.617021 (925 550);
PAINT GREEN (925 550);
FORCEPROP 1 LAST PATH I66
J 0
(975 525);
DISPLAY 0.872340 (975 525);
PAINT AQUA (975 525);
DISPLAY INVISIBLE (975 525);
FORCEPROP 2 LAST CDS_LIB pure_quanta_power
J 0
(925 500);
DISPLAY INVISIBLE (925 500);
FORCEADD GND..1
(-2675 -1650);
FORCEPROP 3 LASTPIN (-2675 -1600) SIG_NAME GND\g
J 0
(-2665 -1590);
DISPLAY 0.659574 (-2665 -1590);
PAINT MONO (-2665 -1590);
DISPLAY INVISIBLE (-2665 -1590);
FORCEPROP 1 LAST PATH I7
J 0
(-2600 -1650);
DISPLAY 0.872340 (-2600 -1650);
PAINT AQUA (-2600 -1650);
DISPLAY INVISIBLE (-2600 -1650);
FORCEPROP 1 LAST HDL_POWER GND
J 0
(-2675 -1500);
DISPLAY 0.872340 (-2675 -1500);
PAINT GREEN (-2675 -1500);
DISPLAY INVISIBLE (-2675 -1500);
FORCEPROP 2 LAST CDS_LIB pure_quanta_power
J 0
(-2675 -1650);
DISPLAY INVISIBLE (-2675 -1650);
FORCEPROP 1 LAST SIZE 1B
J 0
(-2600 -1700);
DISPLAY 0.872340 (-2600 -1700);
PAINT AQUA (-2600 -1700);
DISPLAY INVISIBLE (-2600 -1700);
FORCEADD Q_CAP..1
R 2
(-2675 -1350);
FORCEPROP 1 LAST LOCATION PC1870
J 2
(-2500 -1225);
DISPLAY 0.617021 (-2500 -1225);
PAINT AQUA (-2500 -1225);
FORCEPROP 0 LAST $SEC 1
J 0
(-2725 -1200);
DISPLAY 0.680851 (-2725 -1200);
PAINT MONO (-2725 -1200);
DISPLAY INVISIBLE (-2725 -1200);
FORCEPROP 0 LAST CDS_SEC 1
J 0
(-2725 -1200);
DISPLAY 0.680851 (-2725 -1200);
DISPLAY INVISIBLE (-2725 -1200);
FORCEPROP 1 LASTPIN (-2675 -1250) $PN 1
J 2
(-2685 -1270);
DISPLAY 0.617021 (-2685 -1270);
PAINT MONO (-2685 -1270);
FORCEPROP 1 LASTPIN (-2675 -1450) $PN 2
J 2
(-2685 -1470);
DISPLAY 0.617021 (-2685 -1470);
PAINT MONO (-2685 -1470);
FORCEPROP 1 LAST PART_NUMBER CH4104K1B00
J 0
(-2620 -1517);
DISPLAY 0.617021 (-2620 -1517);
PAINT BLUE (-2620 -1517);
FORCEPROP 1 LAST TOLERANCE 10%
J 0
(-2620 -1370);
DISPLAY 0.617021 (-2620 -1370);
PAINT SKYBLUE (-2620 -1370);
FORCEPROP 1 LAST MATERIAL EMPTY
J 0
(-2620 -1419);
DISPLAY 0.617021 (-2620 -1419);
PAINT RED (-2620 -1419);
FORCEPROP 1 LAST VALUE 0.1UF
J 0
(-2620 -1272);
DISPLAY 0.617021 (-2620 -1272);
PAINT SKYBLUE (-2620 -1272);
FORCEPROP 1 LAST PACK_TYPE 0402
J 0
(-2620 -1468);
DISPLAY 0.617021 (-2620 -1468);
PAINT SKYBLUE (-2620 -1468);
FORCEPROP 1 LAST VOLTAGE 25V
J 0
(-2620 -1321);
DISPLAY 0.617021 (-2620 -1321);
PAINT SKYBLUE (-2620 -1321);
FORCEPROP 1 LAST PATH I8
J 2
(-2725 -1200);
DISPLAY 0.978723 (-2725 -1200);
PAINT WHITE (-2725 -1200);
DISPLAY INVISIBLE (-2725 -1200);
FORCEPROP 2 LAST CDS_LIB pure_quanta
J 0
(-2675 -1350);
DISPLAY INVISIBLE (-2675 -1350);
FORCEADD Q_RES..2
(-2775 -775);
FORCEPROP 1 LAST LOCATION R1571
J 0
(-2825 -675);
DISPLAY 1.021277 (-2825 -675);
PAINT AQUA (-2825 -675);
DISPLAY INVISIBLE (-2825 -675);
FORCEPROP 0 LAST $SEC 1
J 0
(-2725 -600);
DISPLAY 0.680851 (-2725 -600);
PAINT MONO (-2725 -600);
DISPLAY INVISIBLE (-2725 -600);
FORCEPROP 0 LAST CDS_SEC 1
J 0
(-2725 -600);
DISPLAY 1.021277 (-2725 -600);
DISPLAY INVISIBLE (-2725 -600);
FORCEPROP 1 LASTPIN (-2775 -675) $PN 1
J 0
(-2770 -713);
DISPLAY 0.787234 (-2770 -713);
PAINT MONO (-2770 -713);
FORCEPROP 1 LASTPIN (-2775 -875) $PN 2
J 0
(-2770 -865);
DISPLAY 0.787234 (-2770 -865);
PAINT MONO (-2770 -865);
FORCEPROP 1 LAST VALUE 0
J 0
(-2730 -700);
DISPLAY 0.638298 (-2730 -700);
FORCEPROP 1 LAST TOLERANCE 5%
J 0
(-2730 -750);
DISPLAY 0.638298 (-2730 -750);
FORCEPROP 1 LAST WATTAGE 1/16W
J 0
(-2735 -800);
DISPLAY 0.638298 (-2735 -800);
FORCEPROP 1 LAST MATERIAL CHIP
J 0
(-2735 -850);
DISPLAY 0.638298 (-2735 -850);
FORCEPROP 1 LAST PART_NUMBER CS00002JB13
J 0
(-2735 -900);
DISPLAY 0.638298 (-2735 -900);
FORCEPROP 1 LAST PACK_TYPE 0402LF
J 0
(-2735 -950);
DISPLAY 0.638298 (-2735 -950);
FORCEPROP 1 LAST PATH I9
J 0
(-2725 -600);
DISPLAY 0.978723 (-2725 -600);
PAINT WHITE (-2725 -600);
DISPLAY INVISIBLE (-2725 -600);
FORCEPROP 2 LAST CDS_LIB pure_quanta
J 0
(-2775 -775);
DISPLAY INVISIBLE (-2775 -775);
FORCEPROP 1 LAST LOCATION R1571
J 0
(-2725 -650);
DISPLAY 0.638298 (-2725 -650);
FORCEADD DNS..1
(-2575 -1425);
PAINT RED (-2575 -1425);
FORCEPROP 1 LAST COMMENT_BODY TRUE
J 0
(-2575 -1425);
DISPLAY INVISIBLE (-2575 -1425);
FORCEPROP 2 LAST CDS_LIB mstr_misc
J 0
(-2575 -1425);
DISPLAY INVISIBLE (-2575 -1425);
FORCEADD DNS..1
(-1750 -1275);
PAINT RED (-1750 -1275);
FORCEPROP 1 LAST COMMENT_BODY TRUE
J 0
(-1750 -1275);
DISPLAY INVISIBLE (-1750 -1275);
FORCEPROP 2 LAST CDS_LIB mstr_misc
J 0
(-1750 -1275);
DISPLAY INVISIBLE (-1750 -1275);
FORCEADD DNS..1
(-3225 -800);
PAINT RED (-3225 -800);
FORCEPROP 1 LAST COMMENT_BODY TRUE
J 0
(-3225 -800);
DISPLAY INVISIBLE (-3225 -800);
FORCEPROP 2 LAST CDS_LIB mstr_misc
J 0
(-3225 -800);
DISPLAY INVISIBLE (-3225 -800);
FORCEADD DNS..1
(-3225 -1375);
PAINT RED (-3225 -1375);
FORCEPROP 1 LAST COMMENT_BODY TRUE
J 0
(-3225 -1375);
DISPLAY INVISIBLE (-3225 -1375);
FORCEPROP 2 LAST CDS_LIB mstr_misc
J 0
(-3225 -1375);
DISPLAY INVISIBLE (-3225 -1375);
FORCEADD QUANTA_TITLE_BLOCK_C..1
(4525 -3325);
FORCEPROP 0 LAST CDS_CON_LAST_MODIFIED Fri Mar 11 14:53:42 2022
J 0
(2640 -3310);
DISPLAY INVISIBLE (2640 -3310);
FORCEPROP 1 LAST CUSTOM_TXT_CDS <CON_LAST_MODIFIED>
J 0
(2640 -3310);
DISPLAY 0.978723 (2640 -3310);
FORCEPROP 2 LAST CUSTOM_TXT_CDS <XR_PAGE_TITLE>
J 0
(-3365 1925);
DISPLAY 0.638298 (-3365 1925);
PAINT PINK (-3365 1925);
DISPLAY INVISIBLE (-3365 1925);
FORCEPROP 1 LAST CUSTOM_TXT_CDS <NAME_2>
J 0
(1350 -3275);
FORCEPROP 1 LAST CUSTOM_TXT_CDS <NAME_1>
J 0
(1350 -3150);
FORCEPROP 1 LAST CUSTOM_TXT_CDS <Q_NUMBER>
J 0
(3122 -3222);
DISPLAY 1.212766 (3122 -3222);
FORCEPROP 1 LAST CUSTOM_TXT_CDS <Q_PROJ>
J 0
(2143 -3223);
DISPLAY 1.212766 (2143 -3223);
FORCEPROP 1 LAST CUSTOM_TXT_CDS <Q_REV>
J 0
(4341 -3222);
DISPLAY 1.212766 (4341 -3222);
FORCEPROP 1 LAST CUSTOM_TXT_CDS <CON_PAGE_NUM> OF <CON_TOTAL_PAGES>
J 0
(4079 -3307);
DISPLAY 0.978723 (4079 -3307);
FORCEPROP 1 LAST Q_DEPT BU9
J 1
(750 -3275);
DISPLAY 1.957447 (750 -3275);
PAINT GREEN (750 -3275);
FORCEPROP 1 LAST Q_TITLE NCP3284/P3V3_AUX
J 0
(-4750 -3275);
DISPLAY 2.446809 (-4750 -3275);
PAINT GREEN (-4750 -3275);
FORCEPROP 2 LAST CDS_XR_PAGE_TITLE CR-259 : @S9S_MB_2U_LIB.S9S_MB_2U(SCH_1):PAGE259
J 0
(-3365 1925);
DISPLAY 0.638298 (-3365 1925);
PAINT PINK (-3365 1925);
DISPLAY INVISIBLE (-3365 1925);
FORCEPROP 1 LAST COMMENT_BODY TRUE
J 0
(4537 -3338);
DISPLAY 0.978723 (4537 -3338);
PAINT GREEN (4537 -3338);
DISPLAY INVISIBLE (4537 -3338);
FORCEPROP 2 LAST PAGE_BORDER TRUE
J 0
(-3365 1925);
DISPLAY 0.638298 (-3365 1925);
PAINT PINK (-3365 1925);
DISPLAY INVISIBLE (-3365 1925);
FORCEPROP 1 LAST CDS_LMAN_SYM_OUTLINE -9475,6775,100,-125
J 0
(4525 -3325);
DISPLAY 0.468085 (4525 -3325);
PAINT GREEN (4525 -3325);
DISPLAY INVISIBLE (4525 -3325);
FORCEPROP 2 LAST CDS_LIB pure_quanta
J 0
(4525 -3325);
DISPLAY INVISIBLE (4525 -3325);
WIRE 16 -1 (-3275 -1600)(-3275 -1450);
WIRE 16 -1 (-2125 -1275)(-2125 -1250);
WIRE 16 -1 (-1725 -1350)(-1725 -1400);
WIRE 16 -1 (-1325 -1500)(-1325 -1450);
WIRE 16 -1 (-2025 -725)(-2025 -650);
WIRE 16 -1 (-1600 -725)(-1600 -650);
WIRE 16 -1 (-4500 725)(-4500 825);
WIRE 16 -1 (-4375 1125)(-4500 1125);
WIRE 16 -1 (-4500 1125)(-4500 1500);
WIRE 16 -1 (-4500 1025)(-4500 1125);
WIRE 16 -1 (-875 450)(-875 325);
WIRE 16 -1 (325 -1125)(525 -1125);
WIRE 16 -1 (1225 -1875)(1225 -1750);
WIRE 16 -1 (1100 -1175)(1100 -1125);
WIRE 16 -1 (950 -1175)(1100 -1175);
WIRE 16 -1 (-3275 -675)(-3275 -500);
WIRE 16 -1 (925 450)(925 375);
WIRE 16 -1 (-2675 -1600)(-2675 -1450);
WIRE 16 -1 (1375 -25)(925 -25);
WIRE 16 -1 (925 -25)(925 175);
WIRE 16 -1 (325 -25)(925 -25);
FORCEPROP 2 LAST SIG_NAME PWRGD_P3V3_AUX
J 0
(465 -15);
DISPLAY 0.617021 (465 -15);
WIRE 16 3135 (4150 2025)(2750 2025);
WIRE 16 3135 (4150 2600)(4150 2025);
WIRE 16 3135 (2750 2025)(2750 2600);
WIRE 16 3135 (2750 2600)(4150 2600);
WIRE 16 -1 (325 -275)(725 -275);
FORCEPROP 2 LAST SIG_NAME SW_P3V3_AUX_BOOT
J 0
(215 -315);
DISPLAY 0.617021 (215 -315);
WIRE 16 -1 (325 -475)(650 -475);
FORCEPROP 2 LAST SIG_NAME SW_P3V3_AUX_BOOTR
J 0
(215 -515);
DISPLAY 0.617021 (215 -515);
WIRE 16 -1 (750 -1175)(325 -1175);
FORCEPROP 2 LAST SIG_NAME P3V3_AUX_VOS
J 0
(465 -1215);
DISPLAY 0.617021 (465 -1215);
WIRE 16 -1 (-525 -675)(-1050 -675);
FORCEPROP 2 LAST SIG_NAME NC_PU9_4
J 0
(-1060 -665);
DISPLAY 0.617021 (-1060 -665);
WIRE 16 -1 (-525 -625)(-1050 -625);
FORCEPROP 2 LAST SIG_NAME NC_PU9_3
J 0
(-1060 -615);
DISPLAY 0.617021 (-1060 -615);
WIRE 16 -1 (-525 -1275)(-1050 -1275);
FORCEPROP 2 LAST SIG_NAME NC_PU9_1
J 0
(-1060 -1265);
DISPLAY 0.617021 (-1060 -1265);
WIRE 16 -1 (-525 -1325)(-1050 -1325);
FORCEPROP 2 LAST SIG_NAME NC_PU9_2
J 0
(-1060 -1315);
DISPLAY 0.617021 (-1060 -1315);
WIRE 16 2175 (-3950 -1775)(-3950 -2100);
WIRE 16 2175 (-3950 -1775)(-3097 -1775);
WIRE 16 2175 (-3950 -2100)(-3097 -2100);
WIRE 16 2175 (-3097 -1775)(-3097 -2100);
WIRE 16 2175 (-3950 -2175)(-2397 -2175);
WIRE 16 2175 (-3950 -2175)(-3950 -2650);
WIRE 16 2175 (-2397 -2175)(-2397 -2650);
WIRE 16 2175 (-3950 -2650)(-2397 -2650);
WIRE 16 2175 (-2775 475)(-2775 -150);
WIRE 16 2175 (-2775 475)(-1600 475);
WIRE 16 2175 (-2775 -150)(-1600 -150);
WIRE 16 2175 (-1600 475)(-1600 -150);
WIRE 16 -1 (-1325 -1125)(-525 -1125);
WIRE 16 -1 (-1325 -1250)(-1325 -1125);
FORCEPROP 2 LAST SIG_NAME P3V3_AUX_ILIM
J 0
(-1060 -1115);
DISPLAY 0.617021 (-1060 -1115);
WIRE 16 -1 (-1725 -1150)(-1725 -1025);
WIRE 16 -1 (-1725 -1025)(-525 -1025);
FORCEPROP 2 LAST SIG_NAME P3V3_AUX_SS
J 0
(-1060 -1015);
DISPLAY 0.617021 (-1060 -1015);
WIRE 16 -1 (-525 -925)(-2125 -925);
FORCEPROP 2 LAST SIG_NAME P3V3_AUX_MODE
J 0
(-1060 -915);
DISPLAY 0.617021 (-1060 -915);
WIRE 16 -1 (-2125 -925)(-2125 -1050);
WIRE 16 -1 (-525 -825)(-1050 -825);
FORCEPROP 2 LAST SIG_NAME NC_HICCUP
J 0
(-1060 -815);
DISPLAY 0.617021 (-1060 -815);
WIRE 16 -1 (-3275 -1100)(-2775 -1100);
WIRE 16 -1 (-3275 -875)(-3275 -1100);
WIRE 16 -1 (-3275 -1100)(-3275 -1250);
WIRE 16 -1 (-2775 -875)(-2775 -1100);
WIRE 16 -1 (-2775 -1100)(-2675 -1100);
WIRE 16 -1 (-2675 -1100)(-2225 -1100);
WIRE 16 -1 (-2675 -1250)(-2675 -1100);
WIRE 16 -1 (-2225 -1100)(-2225 -875);
WIRE 16 -1 (-2225 -875)(-1200 -875);
WIRE 16 -1 (-1200 -875)(-1200 -475);
WIRE 16 -1 (-1200 -475)(-525 -475);
FORCEPROP 2 LAST SIG_NAME P3V3_AUX_EN
J 0
(-1060 -465);
DISPLAY 0.617021 (-1060 -465);
WIRE 16 -1 (-2775 -675)(-2775 -275);
WIRE 16 -1 (-2775 -275)(-3300 -275);
FORCEPROP 2 LAST SIG_NAME MB0_P12V_STBY_PWRGD
J 0
(-3285 -265);
DISPLAY 0.638298 (-3285 -265);
WIRE 16 -1 (-1675 -325)(-1600 -325);
WIRE 16 -1 (-650 -325)(-1600 -325);
FORCEPROP 2 LAST SIG_NAME P3V3_AUX_VCC
J 0
(-1060 -315);
DISPLAY 0.617021 (-1060 -315);
WIRE 16 -1 (-1600 -325)(-1600 -450);
WIRE 16 -1 (-650 -275)(-650 -325);
WIRE 16 -1 (-525 -275)(-650 -275);
WIRE 16 -1 (-2025 -450)(-2025 -325);
WIRE 16 -1 (-2025 -325)(-2025 -225);
WIRE 16 -1 (-2025 -325)(-1875 -325);
WIRE 16 -1 (-2025 -225)(-525 -225);
FORCEPROP 2 LAST SIG_NAME P3V3_AUX_VDRV
J 0
(-1060 -215);
DISPLAY 0.617021 (-1060 -215);
WIRE 16 -1 (-2075 450)(-2075 375);
WIRE 16 -1 (-2400 450)(-2075 450);
WIRE 16 -1 (-2400 450)(-2400 375);
WIRE 16 -1 (-2725 450)(-2400 450);
WIRE 16 -1 (-2725 450)(-2725 375);
WIRE 16 -1 (-3050 450)(-2725 450);
WIRE 16 -1 (-3050 450)(-3050 375);
WIRE 16 -1 (-3375 450)(-3050 450);
WIRE 16 -1 (-3375 450)(-3375 375);
WIRE 16 -1 (-3700 450)(-3375 450);
WIRE 16 -1 (-3700 450)(-3700 375);
WIRE 16 -1 (-4025 450)(-3700 450);
WIRE 16 -1 (-4025 375)(-4025 450);
WIRE 16 -1 (-4025 1125)(-4025 450);
WIRE 16 -1 (-3950 1125)(-4025 1125);
WIRE 16 -1 (-4025 1125)(-4175 1125);
WIRE 16 -1 (-3950 1125)(-3650 1125);
WIRE 16 -1 (-3950 1025)(-3950 1125);
WIRE 16 -1 (-3650 1125)(-3325 1125);
WIRE 16 -1 (-3650 1025)(-3650 1125);
WIRE 16 -1 (-3325 1125)(-3000 1125);
FORCEPROP 2 LAST SIG_NAME SW_P3V3_AUX_FLT
J 0
(-3085 1125);
DISPLAY 0.617021 (-3085 1125);
WIRE 16 -1 (-3325 1125)(-3325 1025);
WIRE 16 -1 (-3000 1125)(-2675 1125);
WIRE 16 -1 (-3000 1125)(-3000 1025);
WIRE 16 -1 (-2675 1125)(-2350 1125);
WIRE 16 -1 (-2675 1125)(-2675 1025);
WIRE 16 -1 (-2350 1125)(-2025 1125);
WIRE 16 -1 (-2350 1025)(-2350 1125);
WIRE 16 -1 (-1700 1125)(-2025 1125);
WIRE 16 -1 (-2025 1125)(-2025 1025);
WIRE 16 -1 (-1350 1125)(-1700 1125);
WIRE 16 -1 (-1700 1125)(-1700 1025);
WIRE 16 -1 (-1350 1125)(-1350 -75);
WIRE 16 -1 (-525 -75)(-1350 -75);
WIRE 16 -1 (2025 -1775)(1675 -1775);
WIRE 16 -1 (1675 -1775)(1675 -1475);
WIRE 16 -1 (2025 -1475)(1675 -1475);
WIRE 16 -1 (1225 -1475)(1675 -1475);
WIRE 16 -1 (1225 -1550)(1225 -1475);
WIRE 16 -1 (1225 -1475)(1225 -875);
WIRE 16 -1 (325 -875)(1225 -875);
FORCEPROP 2 LAST SIG_NAME P3V3_AUX_FB
J 0
(465 -865);
DISPLAY 0.617021 (465 -865);
WIRE 16 -1 (1175 -475)(1175 -275);
FORCEPROP 2 LAST SIG_NAME SW_P3V3_AUX_BOOT_R
R 3
J 0
(1190 -40);
DISPLAY 0.617021 (1190 -40);
WIRE 16 -1 (850 -475)(1175 -475);
WIRE 16 -1 (1175 -275)(925 -275);
WIRE 16 -1 (2125 -1175)(1675 -1175);
WIRE 16 -1 (2125 -1000)(2125 -1175);
WIRE 16 -1 (2575 -1175)(2125 -1175);
WIRE 16 -1 (1675 -1175)(1675 -1000);
WIRE 16 -1 (2575 -975)(2575 -1175);
WIRE 16 -1 (2975 -1175)(2575 -1175);
WIRE 16 -1 (3350 -1175)(2975 -1175);
WIRE 16 -1 (2975 -1000)(2975 -1175);
WIRE 16 -1 (3350 -1000)(3350 -1175);
WIRE 16 -1 (3750 -1175)(3350 -1175);
WIRE 16 -1 (3750 -1175)(3750 -1000);
WIRE 16 -1 (3750 -1225)(3750 -1175);
WIRE 16 -1 (375 -1275)(375 -1325);
WIRE 16 -1 (325 -1275)(375 -1275);
WIRE 16 -1 (375 -1325)(375 -1375);
WIRE 16 -1 (325 -1325)(375 -1325);
WIRE 16 -1 (-1125 750)(-1125 -25);
WIRE 16 -1 (-1125 750)(-875 750);
WIRE 16 -1 (-1125 825)(-1125 750);
WIRE 16 -1 (-1125 -25)(-525 -25);
WIRE 16 -1 (-875 750)(-875 650);
WIRE 16 -1 (-2075 175)(-2075 25);
WIRE 16 -1 (-2400 25)(-2075 25);
WIRE 16 -1 (-2400 25)(-2400 175);
WIRE 16 -1 (-2725 25)(-2400 25);
WIRE 16 -1 (-2725 25)(-2725 175);
WIRE 16 -1 (-3050 25)(-2725 25);
WIRE 16 -1 (-3050 175)(-3050 25);
WIRE 16 -1 (-3375 25)(-3050 25);
WIRE 16 -1 (-3375 25)(-3375 175);
WIRE 16 -1 (-3700 25)(-3375 25);
WIRE 16 -1 (-4025 25)(-3700 25);
WIRE 16 -1 (-3700 25)(-3700 175);
WIRE 16 -1 (-4025 25)(-4025 175);
WIRE 16 -1 (-4025 25)(-4025 -25);
WIRE 16 -1 (-1700 825)(-1700 675);
WIRE 16 -1 (-1700 675)(-2025 675);
WIRE 16 -1 (-2025 825)(-2025 675);
WIRE 16 -1 (-2350 675)(-2025 675);
WIRE 16 -1 (-2350 825)(-2350 675);
WIRE 16 -1 (-2675 675)(-2350 675);
WIRE 16 -1 (-2675 675)(-2675 825);
WIRE 16 -1 (-3000 675)(-2675 675);
WIRE 16 -1 (-3000 675)(-3000 825);
WIRE 16 -1 (-3325 675)(-3000 675);
WIRE 16 -1 (-3325 675)(-3325 825);
WIRE 16 -1 (-3650 675)(-3325 675);
WIRE 16 -1 (-3650 675)(-3650 825);
WIRE 16 -1 (-3950 675)(-3650 675);
WIRE 16 -1 (-3950 600)(-3950 675);
WIRE 16 -1 (-3950 675)(-3950 825);
WIRE 16 -1 (325 -675)(1350 -675);
FORCEPROP 2 LAST SIG_NAME SW_P3V3_AUX_SW
J 0
(465 -665);
DISPLAY 0.617021 (465 -665);
WIRE 16 -1 (2225 -1775)(2575 -1775);
WIRE 16 -1 (2575 -1775)(2575 -1475);
WIRE 16 -1 (2225 -1475)(2575 -1475);
WIRE 16 -1 (2575 -1475)(4200 -1475);
WIRE 16 -1 (4200 -675)(4200 -1475);
WIRE 16 -1 (4200 -675)(4200 -425);
WIRE 16 -1 (3750 -675)(4200 -675);
WIRE 16 -1 (3750 -800)(3750 -675);
WIRE 16 -1 (3750 -675)(3350 -675);
WIRE 16 -1 (3350 -800)(3350 -675);
WIRE 16 -1 (3350 -675)(2975 -675);
WIRE 16 -1 (2975 -800)(2975 -675);
WIRE 16 -1 (2975 -675)(2575 -675);
WIRE 16 -1 (2575 -775)(2575 -675);
WIRE 16 -1 (2125 -675)(2575 -675);
WIRE 16 -1 (2125 -800)(2125 -675);
WIRE 16 -1 (2125 -675)(1675 -675);
WIRE 16 -1 (1675 -800)(1675 -675);
WIRE 16 -1 (1550 -675)(1675 -675);
DOT 1 (-3000 1125);
DOT 1 (-3275 -1100);
DOT 1 (-2775 -1100);
DOT 1 (-2675 -1100);
DOT 1 (-2025 -325);
DOT 1 (-1600 -325);
DOT 1 (-4500 1125);
DOT 1 (-4025 25);
DOT 1 (-4025 450);
DOT 1 (-3950 675);
DOT 1 (-3700 25);
DOT 1 (-3700 450);
DOT 1 (-3375 25);
DOT 1 (-3375 450);
DOT 1 (-3650 675);
DOT 1 (-3325 675);
DOT 1 (-4025 1125);
DOT 1 (-3950 1125);
DOT 1 (-3650 1125);
DOT 1 (-3325 1125);
DOT 1 (-3050 25);
DOT 1 (-3050 450);
DOT 1 (-2725 25);
DOT 1 (-2725 450);
DOT 1 (-3000 675);
DOT 1 (-2400 25);
DOT 1 (-2400 450);
DOT 1 (-2675 675);
DOT 1 (-2350 675);
DOT 1 (-2675 1125);
DOT 1 (-2350 1125);
DOT 1 (-2025 675);
DOT 1 (-2025 1125);
DOT 1 (-1125 750);
DOT 1 (375 -1325);
DOT 1 (1225 -1475);
DOT 1 (1675 -1475);
DOT 1 (2125 -1175);
DOT 1 (2575 -1475);
DOT 1 (2575 -1175);
DOT 1 (2125 -675);
DOT 1 (2575 -675);
DOT 1 (2975 -1175);
DOT 1 (3350 -1175);
DOT 1 (3750 -1175);
DOT 1 (2975 -675);
DOT 1 (3350 -675);
DOT 1 (3750 -675);
DOT 1 (4200 -675);
DOT 1 (-1700 1125);
DOT 1 (925 -25);
DOT 1 (1675 -675);
FORCENOTE
TO IMPROVE INPUT RIPPLE
(-2725 -100) 0;
DISPLAY LEFT (-2725 -100);
DISPLAY 1.021277 (-2725 -100);
FORCENOTE
TSS=4MS
(-2050 -1600) 0;
DISPLAY LEFT (-2050 -1600);
DISPLAY 1.595745 (-2050 -1600);
PAINT WHITE (-2050 -1600);
FORCENOTE
1ST 
(-3925 -2350) 0;
DISPLAY LEFT (-3925 -2350);
DISPLAY 1.170213 (-3925 -2350);
PAINT WHITE (-3925 -2350);
FORCENOTE
R&C TABLE
(-3925 -2275) 0;
DISPLAY LEFT (-3925 -2275);
DISPLAY 1.170213 (-3925 -2275);
PAINT WHITE (-3925 -2275);
FORCENOTE
PC569 CHANGE TO CH12206KB14
(-3700 -2500) 0;
DISPLAY LEFT (-3700 -2500);
DISPLAY 1.021277 (-3700 -2500);
PAINT WHITE (-3700 -2500);
FORCENOTE
2ND EMPTY PR836
(-3925 -2425) 0;
DISPLAY LEFT (-3925 -2425);
DISPLAY 1.170213 (-3925 -2425);
PAINT WHITE (-3925 -2425);
FORCENOTE
PC8   CHANGE TO CH5473KE902
(-3700 -2575) 0;
DISPLAY LEFT (-3700 -2575);
DISPLAY 1.021277 (-3700 -2575);
PAINT WHITE (-3700 -2575);
FORCENOTE
IC TABLE
(-3925 -1875) 0;
DISPLAY LEFT (-3925 -1875);
DISPLAY 1.170213 (-3925 -1875);
PAINT WHITE (-3925 -1875);
FORCENOTE
2ND AL003889000
(-3925 -2025) 0;
DISPLAY LEFT (-3925 -2025);
DISPLAY 1.021277 (-3925 -2025);
PAINT WHITE (-3925 -2025);
FORCENOTE
1ST AL003284002
(-3925 -1950) 0;
DISPLAY LEFT (-3925 -1950);
DISPLAY 1.021277 (-3925 -1950);
PAINT WHITE (-3925 -1950);
FORCENOTE
BASE ON POC
(-2725 -25) 0;
DISPLAY LEFT (-2725 -25);
DISPLAY 1.021277 (-2725 -25);
FORCENOTE
ESR=9.5M OHM
(-3900 700) 0;
DISPLAY LEFT (-3900 700);
DISPLAY 0.404255 (-3900 700);
FORCENOTE
ESR=9.5M OHM
(-3600 700) 0;
DISPLAY LEFT (-3600 700);
DISPLAY 0.404255 (-3600 700);
FORCENOTE
P3V3_AUX
(-1325 2275) 0;
DISPLAY LEFT (-1325 2275);
DISPLAY 4.914894 (-1325 2275);
PAINT YELLOW (-1325 2275);
FORCENOTE
RB
(1025 -1700) 0;
DISPLAY LEFT (1025 -1700);
DISPLAY 1.021277 (1025 -1700);
FORCENOTE
RA
(1725 -1425) 0;
DISPLAY LEFT (1725 -1425);
DISPLAY 1.021277 (1725 -1425);
FORCENOTE
VO=0.8(1+RA/RB)=3.3V
(2825 -1750) 0;
DISPLAY LEFT (2825 -1750);
DISPLAY 1.021277 (2825 -1750);
PAINT SKYBLUE (2825 -1750);
FORCENOTE
WORK FREQUENCY = 600KHZ
(2775 2050) 0;
DISPLAY LEFT (2775 2050);
DISPLAY 1.021277 (2775 2050);
PAINT WHITE (2775 2050);
FORCENOTE
CURRENT STEP = 10.5A
(2775 2100) 0;
DISPLAY LEFT (2775 2100);
DISPLAY 1.021277 (2775 2100);
PAINT WHITE (2775 2100);
FORCENOTE
IMAX = 21A
(2775 2250) 0;
DISPLAY LEFT (2775 2250);
DISPLAY 1.021277 (2775 2250);
PAINT RED (2775 2250);
FORCENOTE
TDC = 19A
(2775 2300) 0;
DISPLAY LEFT (2775 2300);
DISPLAY 1.021277 (2775 2300);
PAINT RED (2775 2300);
FORCENOTE
DESIGN SPECIFICATION
(2775 2525) 0;
DISPLAY LEFT (2775 2525);
DISPLAY 1.021277 (2775 2525);
PAINT WHITE (2775 2525);
FORCENOTE
SLEW RATE = 2.5A/US
(2775 2150) 0;
DISPLAY LEFT (2775 2150);
DISPLAY 1.021277 (2775 2150);
PAINT WHITE (2775 2150);
FORCENOTE
OCP = 32A
(2775 2200) 0;
DISPLAY LEFT (2775 2200);
DISPLAY 1.021277 (2775 2200);
PAINT RED (2775 2200);
FORCENOTE
TRANSIENT TOLERANCE = 330MV
(2775 2350) 0;
DISPLAY LEFT (2775 2350);
DISPLAY 1.021277 (2775 2350);
PAINT WHITE (2775 2350);
FORCENOTE
OUTPUT VOLTAGE = 3.3V+/-5%
(2775 2450) 0;
DISPLAY LEFT (2775 2450);
DISPLAY 1.021277 (2775 2450);
PAINT WHITE (2775 2450);
FORCENOTE
OUTPUT RIPPLE & NOISE < 50MV
(2775 2400) 0;
DISPLAY LEFT (2775 2400);
DISPLAY 1.021277 (2775 2400);
PAINT WHITE (2775 2400);
FORCENOTE
 EM-15AM17VG1-QS
(1625 -250) 0;
DISPLAY LEFT (1625 -250);
DISPLAY 1.021277 (1625 -250);
FORCENOTE
14.3*12.9*8.0
(1675 -325) 0;
DISPLAY LEFT (1675 -325);
DISPLAY 1.021277 (1675 -325);
FORCENOTE
ISAT=53A@100C
(1675 -400) 0;
DISPLAY LEFT (1675 -400);
DISPLAY 1.021277 (1675 -400);
FORCENOTE
DCR=1.5M OHM
(1675 -475) 0;
DISPLAY LEFT (1675 -475);
DISPLAY 1.021277 (1675 -475);
QUIT
